G04 ================== begin FILE IDENTIFICATION RECORD ==================*
G04 Layout Name:  14545-sa.brd*
G04 Film Name:    L6*
G04 File Format:  Gerber RS274X*
G04 File Origin:  Cadence Allegro 16.5-S056*
G04 Origin Date:  Fri Aug 01 18:35:00 2014*
G04 *
G04 Layer:  VIA CLASS/L6*
G04 Layer:  PIN/L6*
G04 Layer:  ETCH/L6*
G04 Layer:  DRAWING FORMAT/LAYER_PCB_STORY*
G04 Layer:  DRAWING FORMAT/LAYER_L6*
G04 *
G04 Offset:    (0.00 0.00)*
G04 Mirror:    No*
G04 Mode:      Positive*
G04 Rotation:  0*
G04 FullContactRelief:  No*
G04 UndefLineWidth:     6.00*
G04 ================== end FILE IDENTIFICATION RECORD ====================*
%FSLAX35Y35*MOIN*%
%IR0*IPPOS*OFA0.00000B0.00000*MIA0B0*SFA1.00000B1.00000*%
%ADD13O,.103X.06*%
%ADD11C,.022*%
%ADD10C,.028*%
%ADD14C,.173*%
%ADD12C,.156*%
%ADD15C,.02*%
%ADD16C,.04*%
%ADD17C,.025*%
%ADD18C,.006*%
%ADD19C,.0045*%
%ADD20C,.00575*%
%ADD21O,.12702X.08402*%
%ADD27C,.05204*%
%ADD26C,.04604*%
%ADD23C,.09704*%
%ADD22C,.11504*%
%ADD24C,.17004*%
%ADD25C,.18004*%
%ADD28C,.19704*%
G75*
%LPD*%
G75*
G36*
G01X4000Y3000D02*
X3000Y4000D01*
Y207900D01*
X5500Y210400D01*
X23200D01*
X26800Y214000D01*
Y221300D01*
X23800Y224300D01*
X5500D01*
X3000Y226800D01*
Y407300D01*
X5500Y409800D01*
X25200D01*
X29574Y414174D01*
X28999Y414750D01*
Y415493D01*
X29175Y415514D01*
G03X30234Y415924I-276J2286D01*
G01X30372Y416022D01*
X33604Y412789D01*
X33600Y412701D01*
G03X35799Y414900I2300J-101D01*
G01X35711Y414896D01*
X32878Y417729D01*
Y422890D01*
G02X33560Y423173I400J0D01*
G01X79373Y377360D01*
X244182D01*
X280392Y341150D01*
G02X280315Y340524I-283J-283D01*
G03X281600Y336250I1184J-1974D01*
G01X281688Y336254D01*
X282670Y335272D01*
X309501D01*
X374764Y400536D01*
X380100Y395200D01*
X381173D01*
G02X381456Y394517I0J-400D01*
G01X326688Y339750D01*
X326600Y339754D01*
G03X324810Y335890I-101J-2300D01*
G02Y335618I-147J-136D01*
G03X328799Y334155I1689J-1564D01*
G01X328795Y334243D01*
X389751Y395200D01*
X394460D01*
Y389049D01*
X288014Y282604D01*
X253100D01*
G02X252701Y283018I0J400D01*
G03X248099I-2301J82D01*
G02X247700Y282604I-399J-14D01*
G01X227053D01*
G03Y279624I-1755J-1490D01*
G01X236971D01*
G02X237360Y279132I0J-400D01*
G03X241840I2240J-532D01*
G02X242229Y279624I389J92D01*
G01X289248D01*
X395552Y385928D01*
G02X396235Y385645I283J-283D01*
G01X396234Y198392D01*
X297688Y99846D01*
X297600Y99850D01*
G03X299799Y97651I-101J-2300D01*
G01X299795Y97739D01*
X338427Y136371D01*
G02X339110Y136088I283J-283D01*
G01Y67393D01*
X339203Y67299D01*
X339199Y67211D01*
G03X339980Y65380I2300J-101D01*
G02Y64780I-264J-300D01*
G03X343799Y63151I1519J-1730D01*
G01X343795Y63239D01*
X344464Y63908D01*
Y65298D01*
X344876Y65711D01*
Y68509D01*
X344464Y68922D01*
Y97771D01*
G02X345015Y98141I400J0D01*
G03X348166Y99110I984J2409D01*
G02X348832I333J-222D01*
G03X353166I2167J1440D01*
G02X353832I333J-222D01*
G03X358166I2167J1440D01*
G02X358832I333J-222D01*
G03Y101990I2167J1440D01*
G02X358166I-333J222D01*
G03X353832I-2167J-1440D01*
G02X353166I-333J222D01*
G03X348832I-2167J-1440D01*
G02X348166I-333J222D01*
G03X345015Y102959I-2167J-1440D01*
G02X344464Y103329I-151J370D01*
G01Y136397D01*
X402302Y194235D01*
G02X402984Y193952I282J-283D01*
G01Y80142D01*
X382188Y59346D01*
X382100Y59350D01*
G03X380354Y55440I-101J-2300D01*
G02Y55160I-143J-140D01*
G03X384299Y53651I1645J-1610D01*
G01X384295Y53739D01*
X407614Y77058D01*
Y78047D01*
X407738Y78172D01*
Y1572491D01*
X407926Y1572679D01*
Y1578421D01*
X407738Y1578609D01*
Y1730462D01*
X407440Y1730761D01*
Y1730938D01*
X347088Y1791290D01*
X346734D01*
X319197Y1818827D01*
G02X319480Y1819510I283J283D01*
G01X491753D01*
X748473Y1562789D01*
G02X748458Y1562209I-283J-283D01*
G03X751709Y1558958I1542J-1709D01*
G02X752289Y1558973I297J-268D01*
G01X773088Y1538175D01*
Y1535551D01*
G03X772903Y1532216I1489J-1755D01*
G02X772898Y1531661I-291J-275D01*
G03X776216Y1531630I1644J-1611D01*
G02X776221Y1532185I291J275D01*
G03X776066Y1535551I-1644J1611D01*
G01Y1539409D01*
X494874Y1820602D01*
G02X495157Y1821284I283J282D01*
G01X511658D01*
X545058Y1787885D01*
G02X544711Y1787207I-283J-283D01*
G03X546869Y1785049I-411J-2569D01*
G02X547547Y1785396I395J64D01*
G01X789203Y1543739D01*
X789199Y1543651D01*
G03X791497Y1541248I2300J-101D01*
G02X791697Y1541048I0J-200D01*
G03X794001Y1543352I2302J2D01*
G02X793801Y1543552I0J200D01*
G03X791398Y1545850I-2302J-2D01*
G01X791310Y1545846D01*
X774347Y1562809D01*
G02X774456Y1563452I283J283D01*
G03X775457Y1567290I-1129J2344D01*
G02X775524Y1567823I327J230D01*
G03X775777Y1568073I-1698J1972D01*
G02X776377I300J-264D01*
G03X780277I1950J1723D01*
G02X780877I300J-264D01*
G03X782975Y1567198I1950J1723D01*
G02X783374Y1566665I22J-399D01*
G03X784104Y1563846I2453J-869D01*
G02Y1563246I-264J-300D01*
G03X787550I1723J-1950D01*
G02Y1563846I264J300D01*
G03X785679Y1568394I-1723J1950D01*
G02X785280Y1568927I-22J399D01*
G03X780877Y1571519I-2453J869D01*
G02X780277I-300J264D01*
G03X776377I-1950J-1723D01*
G02X775777I-300J264D01*
G03X771697Y1568302I-1950J-1723D01*
G02X771630Y1567769I-327J-230D01*
G03X770983Y1566925I1698J-1972D01*
G02X770340Y1566816I-360J174D01*
G01X512892Y1824264D01*
X98948D01*
G02X98601Y1824861I1J400D01*
G03X98870Y1825618I-2002J1138D01*
G01X98881Y1825681D01*
X99807Y1826606D01*
X541137D01*
X840322Y1527421D01*
Y1522027D01*
X852838Y1509511D01*
Y1479305D01*
G03X855816I1489J-1755D01*
G01Y1510745D01*
X843300Y1523261D01*
Y1525987D01*
G02X843983Y1526270I400J0D01*
G01X858546Y1511707D01*
Y1499115D01*
X859226Y1498436D01*
Y1433391D01*
X767656Y1341821D01*
Y1130117D01*
X770729Y1127044D01*
G02X770676Y1126434I-283J-283D01*
G03X773773Y1126018I1323J-1884D01*
G02X773987Y1126661I308J255D01*
G01X777047Y1129722D01*
G02X777651Y1129677I283J-283D01*
G03X778010Y1129295I1846J1375D01*
G01Y1079084D01*
X896483Y960610D01*
X898744D01*
G03X901345Y959959I1755J1490D01*
G02X901892Y959587I147J-372D01*
G01Y905059D01*
X767518Y770685D01*
Y733424D01*
X767703Y733239D01*
X767699Y733151D01*
G03X770642Y735260I2300J-101D01*
G01X770497Y735302D01*
Y757395D01*
G02X770937Y757793I400J0D01*
G03X773136Y762116I259J2589D01*
G02Y762648I299J266D01*
G03X773146Y762659I-1920J1756D01*
G02X773746I300J-264D01*
G03X777646I1950J1723D01*
G02X778246I300J-264D01*
G03X780344Y761784I1950J1723D01*
G02X780743Y761251I22J-399D01*
G03X781473Y758432I2453J-869D01*
G02Y757832I-264J-300D01*
G03X784919I1723J-1950D01*
G02Y758432I264J300D01*
G03X783048Y762980I-1723J1950D01*
G02X782649Y763513I-22J399D01*
G03X778246Y766105I-2453J869D01*
G02X777646I-300J264D01*
G03X773746I-1950J-1723D01*
G02X773146I-300J264D01*
G03X770937Y766971I-1950J-1723D01*
G02X770498Y767369I-39J398D01*
G01Y769451D01*
X786827Y785780D01*
G02X787510Y785497I283J-283D01*
G01Y737805D01*
G03X789269Y733764I1489J-1755D01*
G02X789713Y733320I47J-397D01*
G03X791729Y735336I2286J-270D01*
G02X791285Y735780I-47J397D01*
G03X790488Y737805I-2286J270D01*
G01Y786931D01*
X904760Y901202D01*
G02X905442Y900919I282J-283D01*
G01Y722291D01*
X855838Y672686D01*
X854451D01*
G03Y669708I-1755J-1489D01*
G01X857072D01*
X906535Y719170D01*
G02X907217Y718887I282J-283D01*
G01X907218Y549427D01*
X767026Y409235D01*
Y337121D01*
X771384Y332763D01*
Y328679D01*
G03X771124Y325427I1489J-1755D01*
G02X771069Y324854I-304J-260D01*
G03X774248Y324547I1430J-1804D01*
G02X774303Y325120I304J260D01*
G03X774362Y328679I-1430J1804D01*
G01Y333997D01*
X770004Y338355D01*
Y340472D01*
G02X770687Y340755I400J0D01*
G01X779042Y332400D01*
G02X779017Y331811I-283J-283D01*
G03X779010Y328295I1482J-1761D01*
G01Y276433D01*
X835703Y219739D01*
X835699Y219651D01*
G03X837898Y221850I2300J-101D01*
G01X837810Y221846D01*
X781988Y277667D01*
Y328295D01*
G03X782260Y328568I-1489J1755D01*
G02X782849Y328593I306J-258D01*
G01X790010Y321433D01*
Y295734D01*
X818183Y267560D01*
X849333D01*
X852104Y264789D01*
X852100Y264701D01*
G03X854299Y266900I2300J-101D01*
G01X854211Y266896D01*
X850567Y270540D01*
X819417D01*
X818074Y271883D01*
G02X818111Y272481I283J283D01*
G03X814881Y275711I-1411J1819D01*
G02X814283Y275674I-315J246D01*
G01X798491Y291465D01*
G02X798521Y292057I283J282D01*
G03X798596Y296021I-1648J2014D01*
G02Y296621I264J300D01*
G03Y300521I-1723J1950D01*
G02Y301121I264J300D01*
G03Y305021I-1723J1950D01*
G02Y305621I264J300D01*
G03X795150I-1723J1950D01*
G02Y305021I-264J-300D01*
G03Y301121I1723J-1950D01*
G02Y300521I-264J-300D01*
G03Y296621I1723J-1950D01*
G02Y296021I-264J-300D01*
G03X794859Y295719I1722J-1951D01*
G02X794267Y295689I-310J253D01*
G01X792988Y296968D01*
Y322667D01*
X771780Y343876D01*
Y356937D01*
G02X772219Y357335I400J0D01*
G03X774418Y361658I259J2589D01*
G02Y362190I299J266D01*
G03X774428Y362201I-1920J1756D01*
G02X775028I300J-264D01*
G03X778928I1950J1723D01*
G02X779528I300J-264D01*
G03X781626Y361326I1950J1723D01*
G02X782025Y360793I22J-399D01*
G03X782755Y357974I2453J-869D01*
G02Y357374I-264J-300D01*
G03X786201I1723J-1950D01*
G02Y357974I264J300D01*
G03X784330Y362522I-1723J1950D01*
G02X783931Y363055I-22J399D01*
G03X779528Y365647I-2453J869D01*
G02X778928I-300J264D01*
G03X775028I-1950J-1723D01*
G02X774428I-300J264D01*
G03X772219Y366513I-1950J-1723D01*
G02X771780Y366911I-39J398D01*
G01Y407262D01*
X787827Y423309D01*
G02X788510Y423026I283J-283D01*
G01Y338305D01*
G03X789137Y334416I1489J-1755D01*
G02X789359Y333898I-150J-371D01*
G03X792361Y335184I2140J-848D01*
G02X792139Y335702I150J371D01*
G03X791488Y338305I-2140J848D01*
G01Y424082D01*
X913746Y546340D01*
Y1493576D01*
X867476Y1539847D01*
G02X867724Y1540528I283J283D01*
G03X865230Y1543022I-201J2293D01*
G02X864549Y1542774I-398J35D01*
G01X829971Y1577352D01*
X824906D01*
X555905Y1846353D01*
G02X556188Y1847036I283J283D01*
G01X800301D01*
X966110Y1681226D01*
Y1652855D01*
G03X967694Y1648800I1490J-1755D01*
G02X968110Y1648400I16J-400D01*
G01Y1640055D01*
G03X971090I1490J-1755D01*
G01Y1643799D01*
G02X971500Y1644199I400J0D01*
G03X973048Y1648255I58J2301D01*
G01Y1668055D01*
G02X973529Y1668447I400J0D01*
G03X975124Y1668691I471J2253D01*
G02X975717Y1668292I196J-349D01*
G03X976876Y1670009I2283J-292D01*
G02X976283Y1670408I-196J349D01*
G03X973529Y1672953I-2283J292D01*
G02X973048Y1673345I-81J392D01*
G01Y1683524D01*
X802979Y1853592D01*
X151808D01*
X150200Y1855200D01*
Y1856694D01*
X151567Y1858060D01*
X831431D01*
X854625Y1881254D01*
X854713Y1881250D01*
G03X852514Y1883449I101J2300D01*
G01X852518Y1883361D01*
X830197Y1861039D01*
X695561D01*
G02X695278Y1861722I0J400D01*
G01X768937Y1935382D01*
G02X769557Y1935314I283J-283D01*
G03X773144Y1938160I1942J1236D01*
G02Y1938440I143J140D01*
G03X772981Y1941811I-1645J1610D01*
G02X772956Y1942400I258J306D01*
G01X778116Y1947560D01*
X790744D01*
G03Y1950540I1755J1490D01*
G01X776882D01*
X692394Y1866052D01*
X147081D01*
X146600Y1866532D01*
Y1868000D01*
X147686Y1869086D01*
X274990D01*
X335288Y1929384D01*
Y1947055D01*
X334399Y1947944D01*
X334403Y1948032D01*
G03X330210Y1946823I-2300J101D01*
G02X330171Y1946554I-165J-113D01*
G03X330510Y1942751I1451J-1787D01*
G01Y1931517D01*
X272834Y1873840D01*
X232074D01*
G02X231737Y1874457I0J400D01*
G03X230113Y1877981I-1937J1243D01*
G02X229885Y1878660I55J396D01*
G01X246970Y1895744D01*
G02X247600Y1895660I283J-282D01*
G03X250740Y1898800I2000J1140D01*
G02X250656Y1899430I198J347D01*
G01X261590Y1910364D01*
Y1914578D01*
X263447Y1916435D01*
Y1917022D01*
X264614Y1918189D01*
G02X265177Y1918192I283J-282D01*
G03X265276Y1918100I1820J1860D01*
G02Y1917500I-264J-300D01*
G03X268722I1723J-1950D01*
G02Y1918100I264J300D01*
G03Y1922000I-1723J1950D01*
G02Y1922600I264J300D01*
G03Y1926500I-1723J1950D01*
G02Y1927100I264J300D01*
G03Y1931000I-1723J1950D01*
G02Y1931600I264J300D01*
G03X268647Y1935564I-1723J1950D01*
G02X268617Y1936156I253J310D01*
G01X278663Y1946202D01*
X283244D01*
G03X286736Y1946181I1755J1489D01*
G02X287286Y1946233I302J-262D01*
G03X286972Y1949552I1423J1809D01*
G02X286422Y1949500I-302J262D01*
G03X283244Y1949180I-1423J-1809D01*
G01X277429D01*
X259671Y1931423D01*
G02X258989Y1931706I-282J283D01*
G01Y1932782D01*
X283267Y1957060D01*
X308190D01*
X308204Y1956876D01*
G03X310398Y1959350I2295J174D01*
G01X310310Y1959346D01*
X309616Y1960040D01*
X308808D01*
G02X308434Y1960581I0J400D01*
G03X307697Y1963473I-2434J920D01*
G02X307630Y1964006I260J303D01*
G03X303803Y1963527I-2130J1494D01*
G02X303870Y1962994I-260J-303D01*
G03X303566Y1960581I2130J-1494D01*
G02X303192Y1960040I-374J-141D01*
G01X296532D01*
G02X296195Y1960654I0J400D01*
G03X295722Y1964000I-2196J1396D01*
G02Y1964600I264J300D01*
G03Y1968500I-1723J1950D01*
G02Y1969100I264J300D01*
G03X292049Y1972773I-1723J1950D01*
G02X291449I-300J264D01*
G03X287776Y1969100I-1950J-1723D01*
G02Y1968500I-264J-300D01*
G03X288059Y1964383I1723J-1950D01*
G02Y1963717I-222J-333D01*
G03X287082Y1960587I1440J-2167D01*
G02X286710Y1960040I-372J-147D01*
G01X282033D01*
X256010Y1934016D01*
Y1912805D01*
G03X255870Y1909423I1489J-1756D01*
G02Y1908858I-283J-283D01*
G01X234656Y1887643D01*
G02X233992Y1887804I-283J283D01*
G03X230261Y1888812I-2192J-704D01*
G02X229671Y1888873I-267J298D01*
G03X225514Y1887412I-1857J-1360D01*
G01X225518Y1887324D01*
X215784Y1877590D01*
X133821D01*
X126348Y1870116D01*
G02X125671Y1870467I-283J283D01*
G03X125694Y1870642I-2279J388D01*
G01X125701Y1870714D01*
X125710Y1870723D01*
X125750Y1871391D01*
X125910Y1874119D01*
X125906Y1874120D01*
X125903Y1874297D01*
G03X121304Y1874581I-2311J-44D01*
G01X121277Y1874391D01*
X121275Y1874392D01*
X121075Y1870994D01*
X121079Y1870993D01*
X121082Y1870816D01*
G03X123785Y1868581I2311J43D01*
G02X124136Y1867904I68J-394D01*
G01X123983Y1867752D01*
X50170D01*
X49459Y1867040D01*
X49458D01*
X28987Y1846570D01*
X28939Y1846555D01*
G03X28552Y1846400I659J-2206D01*
G01X25616D01*
G02X25333Y1847083I0J400D01*
G01X39049Y1860798D01*
X39827D01*
X39854Y1860790D01*
G03Y1865210I646J2210D01*
G01X39827Y1865202D01*
X37225D01*
X20166Y1848142D01*
Y1846400D01*
X3800D01*
X3000Y1847200D01*
Y1944500D01*
X3799Y1945299D01*
X3937Y1945197D01*
G03X3885Y1948863I1366J1853D01*
G01X3746Y1948754D01*
X3000Y1949500D01*
Y1988000D01*
X4000Y1989000D01*
X1029000D01*
X1029999Y1988001D01*
Y1956500D01*
X1030000Y1956499D01*
Y1950500D01*
X1029999D01*
Y1696499D01*
X1028420Y1694920D01*
G02X1027740Y1695158I-283J283D01*
G03X1018345Y1685763I-8449J-946D01*
G02X1018583Y1685083I-45J-397D01*
G01X1015850Y1682350D01*
Y1674050D01*
X1015800Y1674000D01*
Y1624800D01*
X1013000Y1622000D01*
X989000D01*
X984500Y1617500D01*
Y1610000D01*
X989000Y1605500D01*
X1011000D01*
X1016000Y1600500D01*
Y1430000D01*
X1020500Y1425500D01*
X1028000D01*
X1030000Y1423500D01*
Y1270551D01*
X1029999Y1270550D01*
Y4000D01*
X1029500Y3501D01*
Y3500D01*
X1029000Y3000D01*
X4000D01*
G37*
G36*
G01X30478Y1354371D02*
X27296Y1357553D01*
X27300Y1357641D01*
G03X25101Y1355442I-2300J101D01*
G01X25189Y1355446D01*
X27498Y1353137D01*
Y1132581D01*
G02X26816Y1132298I-400J0D01*
G01X24018Y1135095D01*
Y1155644D01*
X24027Y1155671D01*
G03X19607I-2210J646D01*
G01X19616Y1155644D01*
Y1133271D01*
X24298Y1128588D01*
Y1089912D01*
X22838Y1088452D01*
X9423D01*
X9396Y1088460D01*
G03Y1084040I-646J-2210D01*
G01X9423Y1084048D01*
X24662D01*
X26816Y1086202D01*
G02X27498Y1085919I282J-283D01*
G01Y1046867D01*
X16310Y1035679D01*
Y1023683D01*
X20222Y1019772D01*
Y882115D01*
X27498Y874839D01*
Y864217D01*
G02X27033Y863822I-400J0D01*
G03X25916Y863728I-371J-2272D01*
G02X25418Y863950I-130J378D01*
G03X21444Y861687I-2119J-900D01*
G02X21122Y861050I-322J-237D01*
G01X4499D01*
X3000Y862549D01*
Y1192500D01*
X5200Y1194700D01*
X22700D01*
X26700Y1198700D01*
Y1205000D01*
X23000Y1208700D01*
X5200D01*
X3000Y1210900D01*
Y1391900D01*
X5300Y1394200D01*
X22699D01*
X27000Y1398501D01*
Y1404500D01*
X26500Y1405000D01*
X26499D01*
X21999Y1409500D01*
Y1521685D01*
G02X22665Y1521983I400J0D01*
G03X24300Y1521400I1534J1717D01*
G01X24388Y1521404D01*
X24710Y1521082D01*
Y1508883D01*
X28783Y1504810D01*
X36583D01*
X37634Y1503759D01*
Y1394108D01*
G02X36952Y1393825I-400J0D01*
G01X35953Y1394823D01*
X33787Y1396990D01*
X32255D01*
G03X28738Y1394019I-1755J-1490D01*
G02X28472Y1393363I-306J-258D01*
G03X27554Y1388940I27J-2312D01*
G01X27571Y1388923D01*
Y1388922D01*
X27574Y1388920D01*
X31409Y1387252D01*
X31413Y1387261D01*
G03X34644Y1389289I920J2122D01*
G01Y1389300D01*
G03X34645Y1389386I-2312J70D01*
G01X34644D01*
Y1389390D01*
X34646D01*
Y1389393D01*
X34645D01*
G03X33933Y1391052I-2312J-10D01*
G01X33932D01*
G03X33924Y1391060I-1638J-1630D01*
G01Y1391062D01*
G03X33257Y1391503I-1590J-1680D01*
G01X33261Y1391512D01*
X30946Y1392519D01*
G02X31039Y1393262I186J354D01*
G03X32198Y1393946I-539J2238D01*
G01X32257Y1394010D01*
X32553D01*
X33847Y1392717D01*
X35860Y1390705D01*
Y1052717D01*
X31160Y1048018D01*
G02X30478Y1048301I-282J283D01*
G01Y1354371D01*
G37*
G36*
G01X86083Y394952D02*
X84091Y396944D01*
G02X84374Y397627I283J283D01*
G01X345459D01*
G02X345742Y396944I0J-400D01*
G01X343750Y394952D01*
X86083D01*
G37*
G36*
G01X93499Y456550D02*
X92999Y457050D01*
Y463050D01*
X93999Y464050D01*
X110100D01*
X128100Y482050D01*
X137893D01*
G03X140507I1307J2250D01*
G01X141999D01*
X142499Y481550D01*
Y470249D01*
X141800Y469550D01*
X127499D01*
X114499Y456550D01*
X93499D01*
G37*
G36*
G01X62816Y424040D02*
G02X62159Y423898I-374J141D01*
G01X52476Y433580D01*
Y446294D01*
G02X53159Y446577I400J0D01*
G01X72425Y427311D01*
G02X72047Y426640I-283J-283D01*
G03X71048Y426760I-997J-4081D01*
G01X66748D01*
G03X62816Y424040I0J-4202D01*
G37*
G36*
G01X100530Y405931D02*
X77619Y428842D01*
G02X77921Y429524I283J283D01*
G03X81331Y438034I229J4846D01*
G02X81593Y438736I262J302D01*
G01X82058D01*
X114180Y406613D01*
G02X113897Y405931I-283J-282D01*
G01X100530D01*
G37*
G36*
G01X83676Y402380D02*
X68382Y417675D01*
G02X68665Y418358I283J283D01*
G01X71048D01*
G03X75129Y423558I0J4201D01*
G02X75800Y423936I388J95D01*
G01X96673Y403063D01*
G02X96390Y402380I-283J-283D01*
G01X83676D01*
G37*
G36*
G01X117188Y407818D02*
X85179Y439828D01*
G02X85462Y440510I283J282D01*
G01X121932D01*
X139203Y423239D01*
X139199Y423151D01*
G03X142774Y424967I2300J-101D01*
G02Y425633I221J333D01*
G03X142988Y429305I-1275J1917D01*
G01Y435001D01*
X153936Y445948D01*
X156259D01*
X156638Y446328D01*
G02X157318Y446098I283J-283D01*
G03X161900Y446500I2282J301D01*
G01X161896Y446588D01*
X214488Y499181D01*
Y512019D01*
X217380Y514910D01*
X218245D01*
G03Y517890I1755J1490D01*
G01X216146D01*
X211510Y513253D01*
Y500415D01*
X159789Y448695D01*
X159701Y448699D01*
G03X159501I-100J-2300D01*
G01X159413Y448695D01*
X159209Y448899D01*
X201390Y491079D01*
Y552295D01*
G03X198410I-1490J1755D01*
G01Y492313D01*
X197676Y491578D01*
G02X197074Y491620I-283J283D01*
G03X194052Y492474I-2075J-1570D01*
G02X193546Y492673I-146J372D01*
G03X189995Y493857I-2347J-1123D01*
G02X189727Y493940I-92J177D01*
G03X188524Y490701I-2028J-1090D01*
G02X188781Y490588I71J-187D01*
G03X189008Y490147I2416J965D01*
G02X188914Y489614I-337J-215D01*
G03X187919Y487211I1585J-2064D01*
G02X187593Y486766I-397J-51D01*
G03X186245Y485990I407J-2266D01*
G01X176999D01*
X174128Y488861D01*
G02Y489426I283J283D01*
G03X173988Y492808I-1629J1626D01*
G01Y495853D01*
X179068Y500933D01*
Y659030D01*
X279927Y759888D01*
G02X280609Y759605I282J-283D01*
G01Y746805D01*
G03X283663Y743361I1491J-1754D01*
G02X283935I136J-147D01*
G03X285600Y742750I1564J1689D01*
G01X285688Y742754D01*
X344918Y683524D01*
Y409031D01*
G02X344519Y408631I-400J0D01*
G03X342765Y407818I2J-2302D01*
G01X117188D01*
G37*
G36*
G01X29898Y420435D02*
G02X29410Y420045I-400J0D01*
G03X28463Y420060I-509J-2245D01*
G01X28359Y420040D01*
X27617Y420782D01*
G02X27679Y421398I283J283D01*
G03X28695Y423058I-1280J1924D01*
G01X28715Y423236D01*
X28718D01*
X28729Y423547D01*
X28844Y426636D01*
X28836D01*
Y426813D01*
X28828Y426905D01*
G03X24219Y426888I-2304J-185D01*
G01X24214Y426814D01*
X24205Y426805D01*
X24146Y425204D01*
G02X23463Y424936I-400J15D01*
G01X21349Y427050D01*
Y518048D01*
G02X22032Y518331I400J0D01*
G01X29898Y510464D01*
Y420435D01*
G37*
G36*
G01X69872Y443490D02*
X62991Y450371D01*
G02X62996Y450941I283J283D01*
G03X63681Y452907I-1596J1659D01*
G02X64214Y453336I396J53D01*
G03X64899Y457800I786J2164D01*
G01X64811Y457796D01*
X63152Y459454D01*
Y468472D01*
G02X63678Y468852I400J0D01*
G03X66589Y470295I725J2195D01*
G01X66635Y470430D01*
X69345D01*
G03X73357Y472092I0J5674D01*
G01X90615Y489351D01*
G02X91298Y489068I283J-283D01*
G01Y485552D01*
X91916Y484934D01*
G02X91633Y484251I-283J-283D01*
G01X91001D01*
X89798Y483048D01*
Y475052D01*
X91501Y473348D01*
X115497D01*
X132497Y490348D01*
X157497D01*
X163200Y496052D01*
Y502048D01*
X158997Y506252D01*
X150365D01*
G02X150082Y506934I0J400D01*
G01X150200Y507052D01*
Y514048D01*
X148497Y515752D01*
X137811D01*
G02X137469Y516358I0J400D01*
G03X133744Y519040I-1970J1192D01*
G01X130882D01*
X129307Y517464D01*
X129291D01*
X110366Y498540D01*
X109254D01*
G03X108010Y494805I-1755J-1490D01*
G02X108381Y494133I88J-390D01*
G01X106926Y492678D01*
X94907D01*
G02X94624Y493360I0J400D01*
G01X133594Y532330D01*
G03X137226Y541098I-8770J8769D01*
G01Y542763D01*
G02X137666Y543161I400J0D01*
G03Y547741I233J2290D01*
G02X137226Y548139I-40J398D01*
G01Y550916D01*
G02X137742Y551299I400J0D01*
G03X139062Y551290I675J2201D01*
G01X139089Y551298D01*
X140211D01*
X150900Y561988D01*
Y596287D01*
X152565Y597951D01*
G02X153245Y597627I282J-283D01*
G03X162438Y595014I4826J-501D01*
G02X163198Y594839I360J-174D01*
G01Y594356D01*
X157446Y588604D01*
Y576553D01*
G02X157040Y576153I-400J0D01*
G03Y571549I-40J-2302D01*
G02X157446Y571149I6J-400D01*
G01Y556646D01*
G02X156966Y556254I-400J0D01*
G03Y551746I-466J-2254D01*
G02X157446Y551354I80J-392D01*
G01Y511496D01*
X169010Y499933D01*
Y489766D01*
X175765Y483010D01*
X186245D01*
G03X187487Y482256I1755J1490D01*
G02X187681Y481583I-89J-390D01*
G01X175384Y469287D01*
G02X174702Y469570I-282J283D01*
G01Y478198D01*
X172148Y480752D01*
X153001D01*
X144383Y472133D01*
G02X143701Y472416I-282J283D01*
G01Y482048D01*
X142497Y483252D01*
X127602D01*
X109602Y465252D01*
X93501D01*
X91798Y463548D01*
Y456552D01*
X91924Y456426D01*
X91935Y456363D01*
G03X91959Y456238I2567J428D01*
G02X91569Y455752I-390J-86D01*
G01X89552D01*
X87298Y453498D01*
Y444502D01*
X87629Y444172D01*
G02X87346Y443490I-283J-282D01*
G01X69872D01*
G37*
G36*
G01X66715Y474484D02*
X66698Y474665D01*
G03X63677Y476643I-2301J-219D01*
G02X63152Y477023I-125J380D01*
G01Y483799D01*
G02X63707Y484168I400J0D01*
G03X66893Y486007I893J2132D01*
G02X67509Y486078I614J-2616D01*
G01X78821D01*
G03X80873Y486414I-3J6451D01*
G02X81284Y485752I128J-379D01*
G01X70490Y474959D01*
G02X69344Y474484I-1146J1145D01*
G01X66715D01*
G37*
G36*
G01X91499Y483050D02*
X112999D01*
X130999Y501050D01*
X144999D01*
X148999Y505050D01*
X158499D01*
X161999Y501550D01*
Y496550D01*
X156999Y491550D01*
X131999D01*
X114999Y474550D01*
X91999D01*
X90999Y475550D01*
Y482550D01*
X91499Y483050D01*
G37*
G36*
G01X173500Y477700D02*
Y467402D01*
X163724Y457626D01*
X157574D01*
X157499Y457550D01*
X135500D01*
X131815Y453865D01*
G03X128012Y450321I-1815J-1865D01*
G01X128131Y450181D01*
X121950Y444000D01*
X89500D01*
X88500Y445000D01*
Y453000D01*
X90050Y454550D01*
X93193D01*
G03X95807I1307J2250D01*
G01X99034D01*
G03X101966I1466J2150D01*
G01X114999D01*
X128499Y468050D01*
X141999D01*
X153499Y479550D01*
X171650D01*
X173500Y477700D01*
G37*
G36*
G01X87401Y523422D02*
G02X87639Y522741I-45J-398D01*
G01X73014Y508116D01*
X72898D01*
X72283Y507500D01*
X68000D01*
X64900Y504400D01*
X61302D01*
Y531195D01*
X61013Y531484D01*
G02X61105Y532119I283J283D01*
G03X62249Y533605I-1102J2032D01*
G01X62285Y533752D01*
G02X62399Y533756I122J-1856D01*
G01X70044D01*
G02X71289Y533240I0J-1761D01*
G01X79447Y525082D01*
G03X83455Y523422I4008J4009D01*
G01X87401D01*
G37*
G36*
G01X24288Y525648D02*
G03X27755Y523647I2311J0D01*
G02X28354Y523335I200J-346D01*
G01X28426Y522524D01*
Y517116D01*
G02X27743Y516833I-400J0D01*
G01X22402Y522174D01*
Y533302D01*
X24400Y535300D01*
X26723D01*
X28162Y533861D01*
Y531752D01*
G02X27590Y531390I-400J-1D01*
G03X24288Y529302I-991J-2088D01*
G01Y525648D01*
G37*
G36*
G01X80513Y490835D02*
G02X78821Y490134I-1693J1694D01*
G01X67102D01*
G02X66975Y490138I-2J1968D01*
G01X66937Y490281D01*
G03X64629Y492010I-2237J-581D01*
G02X64333Y492693I-13J400D01*
G01X97276Y525636D01*
Y537060D01*
X87847Y546490D01*
X74255D01*
G03X70932Y546685I-1755J-1490D01*
G02X70266Y546907I-272J293D01*
G03X68101Y544200I-2266J-407D01*
G01X68189Y544204D01*
X70883Y541510D01*
X86102D01*
X90668Y536945D01*
G02X90284Y536275I-283J-283D01*
G03X89496Y536376I-788J-3026D01*
G01X88489D01*
X88454Y536533D01*
G03X83888Y536025I-2255J-508D01*
G01Y532250D01*
G03X88137Y530990I2311J0D01*
G02X88872Y530772I335J-218D01*
G01Y529139D01*
X87791Y528057D01*
X87289Y527555D01*
G02X87100Y527476I-190J190D01*
G01X83456D01*
G02X82316Y527949I1J1612D01*
G01X74190Y536075D01*
G03X70001Y537810I-4190J-4192D01*
G01X62302D01*
X62271Y537974D01*
G03X57687Y537547I-2272J-424D01*
G01X57688D01*
X57690Y535774D01*
G02X57007Y535491I-400J0D01*
G01X55990Y536507D01*
Y562315D01*
X48716Y569590D01*
X45972D01*
X37600Y577961D01*
Y608848D01*
G02X38000Y609248I400J0D01*
G03X39539Y609839I-1J2302D01*
G02X39811Y609835I134J-149D01*
G03X40128Y609581I1592J1662D01*
G01X40217Y609414D01*
X40192Y609317D01*
G03X43583Y606354I2010J-1121D01*
G02X43863Y606314I120J-160D01*
G03X47456Y606210I1838J1386D01*
G01X69925D01*
X77832Y598304D01*
X102736D01*
Y544358D01*
X103704Y543389D01*
X103700Y543301D01*
G03X107564Y541511I2300J-101D01*
G02X107836I136J-147D01*
G03X109738Y540923I1564J1689D01*
G02X110194Y540562I58J-395D01*
G01Y521126D01*
G02X109763Y520085I-1473J0D01*
G01X80513Y490835D01*
G37*
G36*
G01X93499Y485050D02*
X92499Y486050D01*
Y490199D01*
X93776Y491476D01*
X107424D01*
X111509Y495560D01*
X111600D01*
X130525Y514486D01*
X130541D01*
X130605Y514550D01*
X147999D01*
X148999Y513550D01*
Y507550D01*
X144499Y503050D01*
X128999D01*
X110999Y485050D01*
X93499D01*
G37*
G36*
G01X28774Y612684D02*
G03X25616Y609526I-1974J-1184D01*
G02X25693Y608900I-206J-343D01*
G01X23376Y606583D01*
Y575638D01*
G02X22694Y575355I-400J0D01*
G01X21999Y576050D01*
Y779600D01*
X22239Y779840D01*
G02X22922Y779557I283J-283D01*
G01Y772772D01*
X27898Y767796D01*
Y701814D01*
X31398Y698314D01*
Y650385D01*
X31334Y650322D01*
Y614541D01*
X29400Y612607D01*
G02X28774Y612684I-283J283D01*
G37*
G36*
G01X41102Y640098D02*
G02X41501Y640498I400J0D01*
G03X43129Y644427I-1J2302D01*
G02Y644992I283J282D01*
G01X43222Y645086D01*
X46971D01*
G02X47271Y644421I0J-400D01*
G03X47510Y641145I1728J-1521D01*
G01Y637884D01*
X50204Y635189D01*
X50200Y635101D01*
G03X52399Y637300I2300J-101D01*
G01X52311Y637296D01*
X50488Y639118D01*
Y641145D01*
G03X51280Y642588I-1489J1756D01*
G01X51303Y642760D01*
X66535D01*
X79381Y655606D01*
X80981D01*
X205159Y779784D01*
X318900D01*
Y776666D01*
X292491D01*
X176090Y660264D01*
Y502167D01*
X172671Y498749D01*
G02X171988Y499031I-283J283D01*
G01Y501167D01*
X160426Y512730D01*
Y574298D01*
G02X160825Y574698I400J0D01*
G03Y579302I-1J2302D01*
G02X160426Y579702I1J400D01*
G01Y587370D01*
X166178Y593122D01*
Y652067D01*
X156299Y661946D01*
X123439D01*
X90033Y628540D01*
X84254D01*
G03Y625560I-1755J-1490D01*
G01X88681D01*
G02X88964Y624878I0J-400D01*
G01X85539Y621452D01*
X81924D01*
X81897Y621461D01*
G03Y617041I-646J-2210D01*
G01X81924Y617050D01*
X86071D01*
G02X86353Y616367I-1J-400D01*
G01X79050Y609063D01*
Y607922D01*
X79041Y607895D01*
G03X83553Y607256I2210J-645D01*
G01Y607339D01*
X128780Y652566D01*
X152414D01*
X153098Y651882D01*
Y642808D01*
X152798Y642507D01*
Y608937D01*
X143298Y599437D01*
Y569411D01*
X141988Y568102D01*
X141973D01*
G03X139661Y564284I-673J-2202D01*
G02X139607Y563677I-285J-281D01*
G03X141191Y559512I1333J-1877D01*
G02X141517Y558831I43J-398D01*
G01X138488Y555802D01*
X138406D01*
G03X137742Y555701I10J-2302D01*
G02X137226Y556083I-116J383D01*
G01Y582395D01*
G03X136309Y584609I-3131J0D01*
G03X130595Y586976I-5716J-5717D01*
G01X123099D01*
G02X121926Y588150I1J1174D01*
G01Y610974D01*
G03X122666Y612682I-1627J1719D01*
G01Y614036D01*
G03X122665Y614047I-1416J-123D01*
G03X121926Y615748I-2367J-17D01*
G01Y616634D01*
G03X122666Y618342I-1627J1719D01*
G01Y619696D01*
G03X122665Y619707I-1416J-123D01*
G03X121926Y621407I-2366J-18D01*
G01Y623229D01*
G02X123008Y625841I3694J0D01*
G02X123448Y626024I441J-439D01*
G01X130670D01*
G03X133608Y627241I-1J4157D01*
G03X135026Y630664I-3423J3423D01*
G01Y639534D01*
G02X135257Y640092I789J0D01*
G01X139857Y644692D01*
G02X140415Y644924I559J-558D01*
G01X141962D01*
X142001Y644774D01*
G03X146550Y645355I2237J581D01*
G01Y649131D01*
G03X141927Y649173I-2312J0D01*
G01X141923Y648984D01*
X140413D01*
G03X136985Y647564I1J-4850D01*
G01X134273Y644851D01*
G02X133658Y645096I-224J331D01*
G03X132021Y646826I-2257J-497D01*
G01X128620Y647776D01*
G03X127407Y643316I-621J-2226D01*
G01X127409D01*
X130779Y642374D01*
G03X131176Y642299I626J2225D01*
G02X131520Y641788I-39J-398D01*
G03X130966Y639538I4296J-2251D01*
G01Y630665D01*
G02X130736Y630112I-781J0D01*
G02X130667Y630084I-68J69D01*
G01X123444D01*
G03X120136Y628713I3J-4683D01*
G03X117866Y623232I5485J-5482D01*
G01Y588150D01*
G03X123099Y582916I5234J0D01*
G01X130593D01*
G02X133166Y581986I0J-4024D01*
G01Y541100D01*
G02X130722Y535202I-8341J1D01*
G01X114629Y519108D01*
G02X114021Y519553I-225J331D01*
G03X114250Y521126I-5300J1575D01*
G01Y625570D01*
G02X115108Y627641I2930J-1D01*
G01X121959Y634492D01*
X122171Y634706D01*
G02X122698Y634924I527J-529D01*
G01X123269D01*
X123316Y634789D01*
G03X127810Y635549I2183J761D01*
G01Y638950D01*
G03X123197Y639158I-2311J0D01*
G01X123180Y638976D01*
X121272D01*
Y638759D01*
G03X119302Y637570I1423J-4584D01*
G01X119088Y637355D01*
X112241Y630508D01*
G03X110196Y625571I4939J-4938D01*
G01Y545872D01*
G02X109738Y545477I-400J1D01*
G03X109299Y545500I-339J-2277D01*
G01X109211Y545496D01*
X107490Y547217D01*
Y595683D01*
X108790Y596983D01*
Y603352D01*
G03X104700Y604699I-1790J1448D01*
G01X104704Y604611D01*
X103883Y603790D01*
X79317D01*
X71717Y611390D01*
X49933D01*
X49913Y611566D01*
G03X45476Y610478I-2287J-266D01*
G02X45191Y609945I-374J-143D01*
G03X44320Y609541I512J-2244D01*
G02X44040Y609581I-120J160D01*
G03X43474Y610114I-1839J-1385D01*
G01X43385Y610281D01*
X43410Y610378D01*
G03X39860Y613211I-2010J1122D01*
G02X39588Y613215I-134J149D01*
G03X38000Y613852I-1590J-1665D01*
G02X37600Y614252I0J400D01*
G01Y615594D01*
X46390Y624383D01*
Y629537D01*
X46912Y630059D01*
X47000Y630055D01*
G03X44801Y632254I101J2300D01*
G01X44805Y632166D01*
X43410Y630771D01*
Y628292D01*
G02X42966Y627895I-400J0D01*
G03X41963Y627785I-257J-2288D01*
G01X41898Y627774D01*
X41714Y627895D01*
G03X39499Y629284I-2114J-911D01*
G01X39411Y629280D01*
X37902Y630789D01*
Y631098D01*
G02X38301Y631498I400J0D01*
G03X40363Y632778I-1J2302D01*
G01X40542Y632889D01*
X40618Y632874D01*
G03X41501Y637302I882J2126D01*
G02X41102Y637702I1J400D01*
G01Y640098D01*
G37*
G36*
G01X32881Y574674D02*
X30070Y577484D01*
X30122Y577608D01*
G03X26940Y580543I-2122J892D01*
G02X26356Y580898I-184J355D01*
G01Y591393D01*
G02X27059Y591653I400J0D01*
G03X30446Y594767I1749J1496D01*
G02X30438Y595039I142J140D01*
G03X27043Y598147I-1738J1510D01*
G02X26355Y598425I-288J278D01*
G01Y605349D01*
X28623Y607617D01*
G02X29304Y607300I283J-283D01*
G03X30231Y605250I2294J-197D01*
G02X30279Y604979I-119J-161D01*
G03X33922Y602183I1921J-1268D01*
G02X34622Y601917I300J-265D01*
G01Y576727D01*
X35992Y575357D01*
G02X35709Y574674I-283J-283D01*
G01X32881D01*
G37*
G36*
G01X34314Y617486D02*
Y626528D01*
G02X34996Y626811I400J0D01*
G01X38201Y623606D01*
X40434D01*
G02X40717Y622924I0J-400D01*
G01X34996Y617203D01*
G02X34314Y617486I-282J283D01*
G37*
G36*
G01X37926Y644969D02*
Y726508D01*
G02X38549Y726840I400J0D01*
G03X41494Y726870I1451J2160D01*
G02X42027Y726803I230J-327D01*
G03X45915Y730262I1973J1697D01*
G02X45982Y730861I295J270D01*
G03X45956Y735156I-1482J2139D01*
G02X45890Y735762I224J331D01*
G03X45914Y739312I-1891J1788D01*
G02X45981Y739911I295J270D01*
G03X42549Y743773I-1482J2139D01*
G02X41949I-300J264D01*
G03X38549Y744211I-1950J-1723D01*
G02X37926Y744543I-223J332D01*
G01Y783380D01*
X34902Y786405D01*
Y786673D01*
G02X35301Y787073I400J0D01*
G03X37352Y790419I-1J2302D01*
G02X37708Y791000I356J181D01*
G01X44157D01*
G03X47218Y792197I943J2100D01*
G01X47233Y792233D01*
X54683Y799683D01*
X54823Y799568D01*
G03X58063Y802808I1458J1782D01*
G01X57948Y802948D01*
X67900Y812900D01*
Y818100D01*
X67731Y818269D01*
X67717Y818319D01*
G03X66119Y819917I-2217J-619D01*
G01X66069Y819931D01*
X63600Y822400D01*
X63349D01*
X63311Y822416D01*
G03X62390Y822602I-907J-2116D01*
G02X62188Y822802I-2J200D01*
G01Y826103D01*
G02X62950Y826274I400J0D01*
G03X66748Y823870I3798J1798D01*
G01X71048D01*
G03Y832272I0J4201D01*
G01X66748D01*
G03X62950Y829868I0J-4202D01*
G02X62188Y830039I-362J171D01*
G01Y840506D01*
G02X62723Y840883I400J0D01*
G03Y845217I776J2167D01*
G02X62188Y845594I-135J377D01*
G01Y999331D01*
G02X62950Y999502I400J0D01*
G03X66748Y997098I3798J1798D01*
G01X71048D01*
G03Y1005500I0J4201D01*
G01X66748D01*
G03X62950Y1003096I0J-4202D01*
G02X62188Y1003267I-362J171D01*
G01Y1009100D01*
X62500D01*
X62600Y1009000D01*
X66278D01*
X66304Y1008993D01*
G03X67696I696J2507D01*
G01X67722Y1009000D01*
X75654D01*
X78541Y1006113D01*
G03X78580Y1006078I286J280D01*
G02X78686Y1005567I-244J-317D01*
G03X79151Y1002746I2013J-1117D01*
G02Y1002154I-269J-296D01*
G03X82829Y999576I1548J-1704D01*
G01X82880Y999700D01*
X95824D01*
Y989994D01*
G02X94734Y987365I-3719J1D01*
G01X84679Y977310D01*
G03X82274Y971501I5811J-5808D01*
G01Y947161D01*
G02X81941Y946359I-1134J1D01*
G01X79733Y944151D01*
G03X77974Y939901I4253J-4249D01*
G01Y932924D01*
G03X78913Y929545I6549J0D01*
G01X78993Y929411D01*
X78883Y929300D01*
X81391Y926791D01*
G02X82472Y924181I-2610J-2610D01*
G01Y845124D01*
X76590D01*
X76050Y844584D01*
X76214Y844421D01*
X76049Y844255D01*
X76019Y844240D01*
G03X74831Y843421I2129J-4359D01*
G02X74290Y843415I-274J291D01*
G03X74022Y843518I-268J-297D01*
G01X72196D01*
G03X72112Y843509I0J-400D01*
G02X71654Y843760I-83J391D01*
G03X67844Y841350I-2155J-810D01*
G02X67749Y840722I-288J-278D01*
G03X70515Y840306I1111J-2016D01*
G02X70610Y840934I288J278D01*
G03X71040Y841239I-1108J2018D01*
G01X71181Y841366D01*
X72111Y840436D01*
Y839455D01*
X72658Y838909D01*
G03X73025Y838801I283J283D01*
G02X73493Y838522I84J-391D01*
G03X80699Y835754I4657J1360D01*
G02X81235Y835645I210J-341D01*
G03X81561Y835476I327J231D01*
G01X82472D01*
Y819197D01*
G02X81840Y818872I-400J0D01*
G03Y815128I-1340J-1872D01*
G02X82472Y814803I232J-325D01*
G01Y717000D01*
G02X81399Y714409I-3665J0D01*
G01X67995Y701005D01*
G02X64429Y699528I-3566J3566D01*
G01X52953D01*
G02X52574Y699559I-1J2325D01*
G03X48001Y699089I-2274J-359D01*
G01Y699088D01*
X48108Y695764D01*
Y695763D01*
G03X52684Y695443I2302J37D01*
G02X53066Y695474I379J-2298D01*
G01X64428D01*
G03X69636Y697113I-1J9096D01*
G01X69774Y697209D01*
X69853Y697130D01*
X84266Y711543D01*
G03X86526Y716999I-5459J5457D01*
G01Y786109D01*
G02X87208Y786392I400J0D01*
G01X88100Y785500D01*
X107913D01*
X109077Y784336D01*
X202020D01*
G02X202303Y783653I0J-400D01*
G01X163280Y744629D01*
G02X162622Y745051I-283J283D01*
G03X159752Y742181I-4551J1681D01*
G02X160174Y741523I139J-375D01*
G01X83442Y664792D01*
G02X82767Y664997I-283J283D01*
G03X80499Y666862I-2268J-447D01*
G01X76999D01*
G03Y662238I0J-2312D01*
G01X79923D01*
G02X80206Y661556I0J-400D01*
G01X79011Y660360D01*
X77411D01*
X65115Y648064D01*
X41988D01*
X38609Y644686D01*
G02X37926Y644969I-283J283D01*
G37*
G36*
G01X26448Y781411D02*
G03X28788Y785305I851J2139D01*
G01Y786390D01*
X29465Y787066D01*
G02X30148Y786783I283J-283D01*
G01Y770725D01*
G02X29465Y770442I-400J0D01*
G01X25900Y774006D01*
Y781039D01*
G02X26448Y781411I400J0D01*
G37*
G36*
G01X31400Y862100D02*
X30476Y863024D01*
Y876073D01*
X23200Y883349D01*
Y1018602D01*
G02X23883Y1018885I400J0D01*
G01X35860Y1006909D01*
Y865966D01*
X31994Y862100D01*
X31400D01*
G37*
G36*
G01X177947Y829753D02*
X167000Y840700D01*
X147831D01*
X145408Y843124D01*
X100946D01*
X100904Y843266D01*
G03X97204Y844350I-2204J-666D01*
G02X96592Y844464I-260J304D01*
G03X96240Y844674I-352J-190D01*
G01X86526D01*
Y924180D01*
G03X85262Y928420I-7744J0D01*
G01X85173Y928556D01*
X85266Y928649D01*
X82758Y931158D01*
G02X82026Y932923I1765J1766D01*
G01Y939900D01*
G02X82600Y941284I1959J-1D01*
G01X85816Y944501D01*
X85676Y944642D01*
X85743Y944772D01*
G03X86326Y947161I-4604J2389D01*
G01Y971500D01*
G02X87546Y974443I4163J-1D01*
G01X98609Y985507D01*
X98516Y985600D01*
X98605Y985736D01*
G03X99876Y989993I-6500J4259D01*
G01Y1054127D01*
G02X100608Y1055892I2497J-1D01*
G01X121593Y1076877D01*
G02X122251Y1076731I282J-283D01*
G03X126160Y1075998I2172J792D01*
G02X126860Y1075734I300J-264D01*
G01Y1066854D01*
X130954Y1062760D01*
X162167D01*
X197388Y1097981D01*
X197888Y1099191D01*
Y1171822D01*
X326866Y1300800D01*
X329672D01*
Y1268977D01*
X333860Y1264789D01*
Y1094031D01*
X310690Y1070862D01*
X307634Y1067801D01*
Y1067640D01*
X176483Y936490D01*
X172855D01*
G03X172331Y936945I-1754J-1491D01*
G02X172316Y937611I214J338D01*
G03X173210Y940146I-1316J1889D01*
G01X173202Y940173D01*
Y943788D01*
X175652Y946238D01*
Y950738D01*
X170738Y955652D01*
X169009D01*
X165259Y959402D01*
X155195D01*
G02X154796Y959831I0J400D01*
G03X152399Y962300I-2296J169D01*
G01X152311Y962296D01*
X106090Y1008517D01*
Y1050258D01*
X112510Y1056678D01*
X112598Y1056674D01*
G03X114498Y1057538I101J2300D01*
G02X115210Y1057288I312J-250D01*
G01Y1019183D01*
X153087Y981307D01*
G02X153092Y980747I-283J-283D01*
G03X156347Y977492I1657J-1598D01*
G02X156907Y977487I277J-288D01*
G01X169960Y964433D01*
Y962068D01*
G03X172940Y963102I2040J-1068D01*
G01Y965667D01*
X158126Y980480D01*
Y980548D01*
X156148Y982526D01*
X156080D01*
X118190Y1020417D01*
Y1061745D01*
G03X115210I-1490J1755D01*
G01Y1060660D01*
G02X114498Y1060410I-400J0D01*
G03X110399Y1058873I-1799J-1436D01*
G01X110403Y1058785D01*
X103110Y1051492D01*
Y1007283D01*
X150204Y960189D01*
X150200Y960101D01*
G03X150204Y959831I2300J-101D01*
G02X149805Y959402I-399J-29D01*
G01X147764D01*
X115064Y992102D01*
X105373D01*
X105346Y992110D01*
G03X103040Y988305I-646J-2210D01*
G02X102818Y987634I-289J-277D01*
G03X103846Y983154I383J-2270D01*
G01X103873Y983162D01*
X104357D01*
Y982795D01*
X104193Y982766D01*
G03X105246Y978290I407J-2266D01*
G01X105273Y978298D01*
X110588D01*
X140288Y948598D01*
X153591D01*
X156648Y945542D01*
X156661Y945488D01*
G03X159815Y948642I2525J629D01*
G01X159761Y948655D01*
X157301Y951116D01*
G02X157584Y951799I283J283D01*
G01X162109D01*
X167609Y946299D01*
X168519D01*
G02X168802Y945616I0J-400D01*
G01X168798Y945612D01*
Y940173D01*
X168790Y940146D01*
G03X169769Y937555I2210J-646D01*
G02X169784Y936889I-214J-338D01*
G03X169931Y933017I1316J-1889D01*
G02X170003Y932745I-101J-172D01*
G03X173909Y932887I1997J-1145D01*
G02X174240Y933510I332J223D01*
G01X177717D01*
X308726Y1064519D01*
G02X309409Y1064236I283J-283D01*
G01Y1014501D01*
X222504Y927596D01*
G02X221858Y927710I-283J283D01*
G03X217549Y928336I-2359J-1097D01*
G02X216949I-300J264D01*
G03Y924890I-1950J-1723D01*
G02X217549I300J-264D01*
G03X218402Y924254I1949J1724D01*
G02X218516Y923608I-169J-363D01*
G01X199310Y904402D01*
Y898355D01*
G03X202288I1489J-1755D01*
G01Y903168D01*
X310501Y1011380D01*
G02X311184Y1011097I283J-283D01*
G01Y962990D01*
X177947Y829753D01*
G37*
G36*
G01X60700Y1047400D02*
X58638Y1049462D01*
Y1156072D01*
X105973Y1203406D01*
X106061Y1203402D01*
G03X103862Y1205601I101J2300D01*
G01X103866Y1205513D01*
X57371Y1159018D01*
G02X56688Y1159301I-283J283D01*
G01Y1409434D01*
X60851Y1413596D01*
G02X61533Y1413313I282J-283D01*
G01Y1409060D01*
X61470Y1408997D01*
Y1404625D01*
X61534Y1404562D01*
Y1371860D01*
X75462Y1357931D01*
X75458Y1357843D01*
G03X77657Y1360042I2300J-101D01*
G01X77569Y1360038D01*
X64512Y1373094D01*
Y1402591D01*
G02X65072Y1402958I400J0D01*
G03X66748Y1402610I1674J3853D01*
G01X71048D01*
G03Y1411012I0J4201D01*
G01X66748D01*
G03X65072Y1410664I-2J-4201D01*
G02X64512Y1411031I-160J367D01*
G01Y1414747D01*
X79264Y1429499D01*
Y1429588D01*
X79378Y1429701D01*
Y1433229D01*
X58688Y1453918D01*
Y1521777D01*
X60239Y1525520D01*
X77816Y1543097D01*
G02X78387Y1543092I283J-282D01*
G03X81705Y1543099I1656J1599D01*
G02X82281Y1543101I289J-277D01*
G03X82270Y1546297I1651J1604D01*
G02X81694Y1546295I-289J277D01*
G03X81642Y1546347I-1654J-1602D01*
G02X81637Y1546918I277J288D01*
G01X88428Y1553710D01*
G03X88864Y1554763I-1054J1053D01*
G01Y1554839D01*
X90230Y1558935D01*
X90311Y1558971D01*
G03X87950Y1562882I-937J2102D01*
G02X87391Y1562946I-247J315D01*
G03X84110Y1559745I-1791J-1446D01*
G01Y1557879D01*
G02X83521Y1557527I-400J0D01*
G03X80852Y1557177I-1092J-2027D01*
G02X80577I-138J145D01*
G03X78863Y1557798I-1577J-1677D01*
G02X78440Y1558197I-23J399D01*
G01Y1559398D01*
G02X78636Y1559598I200J0D01*
G03X77019Y1563573I-36J2302D01*
G02X76486Y1563558I-275J291D01*
G03X73510Y1560045I-1486J-1758D01*
G01Y1552011D01*
X69733Y1548234D01*
G02X69050Y1548517I-283J283D01*
G01Y1561744D01*
X77864Y1570558D01*
G02X78480Y1570495I282J-283D01*
G03X79908Y1569517I1919J1271D01*
G02X80194Y1568977I-85J-391D01*
G03X82821Y1570366I2135J-860D01*
G02X82535Y1570906I85J391D01*
G03X81671Y1573686I-2135J861D01*
G02X81608Y1574302I220J334D01*
G01X84217Y1576910D01*
X93417D01*
X136404Y1619898D01*
Y1698497D01*
X136468Y1698560D01*
Y1701358D01*
X136404Y1701421D01*
Y1708034D01*
G03X137775Y1709806I-905J2116D01*
G02X138453Y1710029I395J-60D01*
G01X142657Y1705825D01*
G02X144574Y1701199I-4625J-4627D01*
G01Y1678184D01*
G03X146216Y1672967I9110J0D01*
G01X146312Y1672829D01*
X146233Y1672750D01*
X163991Y1654991D01*
G02X165574Y1651172I-3819J-3820D01*
G01Y1597500D01*
G02X163163Y1591681I-8231J1D01*
G01X136426Y1564944D01*
G03X132722Y1556003I8944J-8943D01*
G01Y1539072D01*
G03X131982Y1537364I1627J-1719D01*
G01Y1536010D01*
G03X131983Y1535999I1416J123D01*
G03X132722Y1534298I2367J17D01*
G01Y1533412D01*
G03X131982Y1531704I1627J-1719D01*
G01Y1530350D01*
G03X131983Y1530339I1416J123D01*
G03X132722Y1528638I2367J17D01*
G01Y1527752D01*
G03X131982Y1526044I1627J-1719D01*
G01Y1524690D01*
G03X131983Y1524679I1416J123D01*
G03X132722Y1522978I2367J17D01*
G01Y1522092D01*
G03X131982Y1520384I1627J-1719D01*
G01Y1519030D01*
G03X131983Y1519019I1416J123D01*
G03X132665Y1517375I2366J18D01*
G01X132722Y1517317D01*
X132723Y1516433D01*
X132665Y1516375D01*
G03X131982Y1514724I1684J-1663D01*
G01Y1513370D01*
G03X131983Y1513359I1416J123D01*
G03X132722Y1511658I2367J17D01*
G01Y1440114D01*
G03X131982Y1438407I1627J-1719D01*
G01Y1437053D01*
G03X131983Y1437042I1416J123D01*
G03X132722Y1435341I2366J17D01*
G01Y1434454D01*
G03X131982Y1432747I1627J-1719D01*
G01Y1431393D01*
G03X131983Y1431382I1416J123D01*
G03X132722Y1429681I2366J17D01*
G01Y1428794D01*
G03X131982Y1427087I1627J-1719D01*
G01Y1425733D01*
G03X131983Y1425722I1416J123D01*
G03X132722Y1424021I2366J17D01*
G01Y1423134D01*
G03X131982Y1421427I1627J-1719D01*
G01Y1420073D01*
G03X131983Y1420062I1416J123D01*
G03X132722Y1418361I2366J17D01*
G01Y1417474D01*
G03X131982Y1415767I1627J-1719D01*
G01Y1414413D01*
G03X131983Y1414402I1416J123D01*
G03X132722Y1412701I2366J17D01*
G01Y1352500D01*
G02X131478Y1349496I-4249J0D01*
G01X130991Y1349009D01*
G02X129410Y1348354I-1581J1581D01*
G01X116462D01*
G02X115794Y1348435I-4J2762D01*
G03X111188Y1348154I-2294J-281D01*
G01Y1344500D01*
G03X115794Y1344219I2312J0D01*
G02X116462Y1344300I664J-2681D01*
G01X129411D01*
G03X133858Y1346142I0J6290D01*
G01X134345Y1346629D01*
G03X136776Y1352499I-5872J5870D01*
G01Y1556000D01*
G02X139293Y1562077I8594J0D01*
G01X166030Y1588814D01*
G03X169626Y1597499I-8688J8684D01*
G01Y1651173D01*
G03X167888Y1656635I-9454J-1D01*
G01X167790Y1656773D01*
X167866Y1656849D01*
X150108Y1674608D01*
G02X148626Y1678184I3575J3577D01*
G01Y1701202D01*
G03X145524Y1708692I-10596J-1D01*
G01X127599Y1726616D01*
X127531Y1726549D01*
X127393Y1726651D01*
G03X121078Y1728726I-6316J-8574D01*
G01X117592D01*
G02X117309Y1729409I0J400D01*
G01X123200Y1735300D01*
Y1739072D01*
X183442D01*
G02X184736Y1738536I0J-1830D01*
G01X187136Y1736136D01*
G02X187648Y1734902I-1234J-1235D01*
G01Y1602569D01*
G03X186908Y1600869I1626J-1719D01*
G01Y1599504D01*
G03X187648Y1597796I2366J11D01*
G01Y1596909D01*
G03X186908Y1595209I1626J-1719D01*
G01Y1593844D01*
G03X187590Y1592193I2366J11D01*
G01X187647Y1592135D01*
X187648Y1591251D01*
X187590Y1591193D01*
G03X186908Y1589549I1684J-1662D01*
G01Y1588184D01*
G03X187590Y1586533I2366J11D01*
G01X187647Y1586475D01*
X187648Y1585591D01*
X187590Y1585533D01*
G03X186908Y1583889I1684J-1662D01*
G01Y1582524D01*
G03X187647Y1580816I2367J10D01*
G01Y1565942D01*
G03X186908Y1564242I1627J-1718D01*
G01Y1562877D01*
G03X187648Y1561169I2366J11D01*
G01Y1123371D01*
G02X186441Y1120459I-4118J1D01*
G01X148352Y1082370D01*
G02X146000Y1081396I-2352J2353D01*
G01X145600D01*
Y1081600D01*
X143900Y1083300D01*
X138368D01*
X138332Y1083314D01*
G03X136622I-855J-2137D01*
G01X136586Y1083300D01*
X133490D01*
Y1088517D01*
X130890Y1091117D01*
Y1092134D01*
G02X131469Y1092492I400J0D01*
G03Y1096608I1030J2058D01*
G02X130890Y1096966I-179J358D01*
G01Y1097766D01*
X126295Y1102361D01*
X126299Y1102449D01*
G03X124100Y1100250I-2300J101D01*
G01X124188Y1100254D01*
X127910Y1096532D01*
Y1093452D01*
G02X127272Y1093130I-400J-1D01*
G03X124197Y1089734I-1372J-1848D01*
G02X123901Y1089064I-296J-270D01*
G01X119730D01*
G02X119447Y1089747I0J400D01*
G01X120500Y1090800D01*
Y1091292D01*
G02X120878Y1091692I400J1D01*
G03X118994Y1095480I-129J2298D01*
G01X110902D01*
X62823Y1047400D01*
X60700D01*
G37*
G36*
G01X37959Y1507648D02*
X37817Y1507790D01*
X30017D01*
X27690Y1510117D01*
Y1510936D01*
X28011D01*
X28067Y1510829D01*
G03X30219Y1509591I2048J1071D01*
G01X33615Y1509742D01*
G03X35802Y1511736I-103J2309D01*
G01X35807Y1511775D01*
G03X33409Y1514360I-2295J276D01*
G01X30012Y1514209D01*
G03X28388Y1513437I102J-2310D01*
G02X27690Y1513702I-298J266D01*
G01Y1522316D01*
X26495Y1523511D01*
X26499Y1523599D01*
G03X22665Y1525417I-2300J101D01*
G02X21999Y1525715I-266J298D01*
G01Y1529399D01*
X24600Y1532000D01*
X24724D01*
X32239Y1524484D01*
G02X31963Y1523802I-283J-282D01*
G03X29780Y1520886I36J-2302D01*
G01X29788Y1520860D01*
Y1518486D01*
X29780Y1518460D01*
G03X34218I2219J-614D01*
G01X34210Y1518486D01*
Y1520860D01*
X34218Y1520886D01*
G03X34155Y1522307I-2219J614D01*
G02X34529Y1522848I374J141D01*
G01X35316D01*
X38300Y1519864D01*
Y1507789D01*
G02X37959Y1507648I-200J1D01*
G37*
G36*
G01X67910Y1564817D02*
G02X67228Y1565100I-282J283D01*
G01Y1575021D01*
X74611Y1582404D01*
X74699Y1582400D01*
G03X72500Y1584599I101J2300D01*
G01X72504Y1584511D01*
X66135Y1578142D01*
G02X65452Y1578425I-283J283D01*
G01Y1634582D01*
G02X65930Y1634974I400J-1D01*
G03X66748Y1634894I816J4121D01*
G01X71048D01*
G03Y1643296I0J4201D01*
G01X66748D01*
G03X65529Y1643116I-2J-4201D01*
G02X65012Y1643498I-117J383D01*
G01Y1680406D01*
X74311Y1689704D01*
X74399Y1689700D01*
G03X75151Y1694208I101J2300D01*
G02X74981Y1694875I113J384D01*
G01X93017Y1712910D01*
X102404D01*
X102465Y1712971D01*
G02X103148Y1712697I283J-283D01*
G03X107440Y1710771I2601J52D01*
G02X107724Y1710747I130J-152D01*
G03X108206Y1714118I1775J1466D01*
G02X107926Y1714174I-113J165D01*
G03X107709Y1714460I-2176J-1426D01*
G02X108010Y1715124I301J264D01*
G01X110998D01*
G03X114216Y1718391I1755J1489D01*
G02X114187Y1718983I254J309D01*
G03X111099Y1718835I-1626J1630D01*
G02X111128Y1718243I-254J-309D01*
G03X110998Y1718102I1626J-1629D01*
G01X103383D01*
X101170Y1715890D01*
X91783D01*
X62279Y1686385D01*
G02X61596Y1686668I-283J283D01*
G01Y1692413D01*
G03X61248Y1692809I-400J0D01*
G02X60900Y1693206I52J397D01*
G01Y1700237D01*
X58999Y1702137D01*
Y1716374D01*
X67042D01*
G03X71524Y1717731I-1J8085D01*
G01X71661Y1717822D01*
X71750Y1717733D01*
X77059Y1723041D01*
G02X78344Y1724000I3942J-3941D01*
G01X111900D01*
X112574Y1724674D01*
X121077D01*
G02X125741Y1722741I-1J-6597D01*
G01X135378Y1713104D01*
G02X135155Y1712426I-283J-283D01*
G03X133842Y1711748I344J-2276D01*
G02X133562Y1711740I-144J139D01*
G03X132100Y1707750I-1563J-1690D01*
G01X132188Y1707754D01*
X133426Y1706517D01*
Y1702660D01*
G02X133035Y1702260I-400J0D01*
G03Y1697658I55J-2301D01*
G02X133426Y1697258I-9J-400D01*
G01Y1621132D01*
X92183Y1579890D01*
X82983D01*
X77672Y1574579D01*
G02X76991Y1574823I-283J283D01*
G03X74477Y1572309I-2291J-223D01*
G02X74721Y1571628I-39J-398D01*
G01X67910Y1564817D01*
G37*
G36*
G01X73123Y1772160D02*
X74774Y1773812D01*
X297614D01*
X299265Y1772160D01*
G02X298982Y1771477I-283J-283D01*
G01X73406D01*
G02X73123Y1772160I0J400D01*
G37*
G36*
G01X76842Y1784190D02*
X71183Y1789849D01*
X71072Y1789821D01*
G02X68872Y1790421I-574J2229D01*
G03X68307I-282J-283D01*
G01X64275Y1786389D01*
Y1772640D01*
X62896Y1771262D01*
G02X62213Y1771545I-283J283D01*
G01Y1789647D01*
X72662Y1800097D01*
G02X73342Y1799867I283J-283D01*
G03X81962Y1803513I4808J645D01*
G02X82276Y1804160I314J247D01*
G01X122701D01*
X138439Y1788422D01*
G02X138156Y1787740I-283J-282D01*
G01X119416D01*
X108316Y1798840D01*
X87354D01*
G03Y1795860I-1755J-1490D01*
G01X107082D01*
X116070Y1786872D01*
G02X115787Y1786190I-283J-282D01*
G01X103154D01*
G03X99099Y1784606I-1755J-1490D01*
G02X98699Y1784190I-400J-16D01*
G01X76842D01*
G37*
G36*
G01X191700Y1734904D02*
G03X190003Y1739003I-5799J0D01*
G01X186594Y1742411D01*
X186470Y1742288D01*
X186338Y1742363D01*
G03X183443Y1743126I-2898J-5120D01*
G01X122306D01*
G03X119737Y1742615I4J-6733D01*
G01X119700Y1742600D01*
X117100D01*
X109050Y1734550D01*
X60350D01*
X58999Y1735901D01*
Y1748086D01*
X71373Y1760460D01*
X94334D01*
X98726Y1756067D01*
G02X98674Y1755457I-282J-283D01*
G03X100100Y1751275I1325J-1882D01*
G01X100188Y1751279D01*
X100407Y1751060D01*
X183656D01*
X324584Y1610132D01*
Y1558591D01*
X322710Y1556717D01*
Y1305879D01*
X192383Y1175552D01*
G02X191700Y1175834I-283J283D01*
G01Y1734904D01*
G37*
G36*
G01X205344Y1789515D02*
X205106Y1789752D01*
X168580D01*
G02X168183Y1790204I0J400D01*
G03X164743Y1792490I-2283J296D01*
G02X164151Y1792920I-201J346D01*
G03X163057Y1791410I-2251J480D01*
G02X163649Y1790980I201J-346D01*
G03X163617Y1790204I2251J-481D01*
G02X163220Y1789752I-397J-52D01*
G01X141322D01*
X124115Y1806960D01*
X123211Y1807140D01*
X76217D01*
X75314Y1806960D01*
X74190Y1805837D01*
X73924Y1805659D01*
X73003Y1804738D01*
X72825Y1804473D01*
X60996Y1792643D01*
G02X60313Y1792926I-283J283D01*
G01Y1812495D01*
X67818Y1820000D01*
X86960D01*
G02X87101Y1819659I-1J-200D01*
G01X86838Y1819396D01*
X86750Y1819400D01*
G03X84453Y1816409I-101J-2300D01*
G02X84071Y1815890I-382J-119D01*
G01X83566D01*
X82395Y1817061D01*
X82399Y1817149D01*
G03X80200Y1814950I-2300J101D01*
G01X80288Y1814954D01*
X82332Y1812910D01*
X89017D01*
X92808Y1816702D01*
X94627D01*
X95660Y1817734D01*
X154317D01*
G02X154603Y1817055I0J-400D01*
G03X161539I3468J-3393D01*
G02X161825Y1817734I286J279D01*
G01X316076D01*
X333843Y1799968D01*
G02X333752Y1799334I-283J-283D01*
G03X337283Y1795803I1247J-2284D01*
G02X337917Y1795894I351J-192D01*
G01X343613Y1790197D01*
G02X343330Y1789515I-283J-282D01*
G01X205344D01*
G37*
G36*
G01X139291Y428201D02*
G02X138624Y428031I-384J113D01*
G01X124338Y442317D01*
G02X124621Y443000I283J283D01*
G01X126000D01*
X138000Y455000D01*
X137334Y455666D01*
G02X137617Y456349I283J283D01*
G01X158001D01*
X158076Y456425D01*
X161556D01*
G02X161839Y455742I0J-400D01*
G01X155025Y448928D01*
X152702D01*
X140383Y436609D01*
G02X139701Y436879I-282J283D01*
G03X139275Y435372I-2601J-79D01*
G02X140010Y435153I335J-219D01*
G01Y429305D01*
G03X139291Y428201I1489J-1756D01*
G37*
G36*
G01X162438Y599238D02*
G03X157570Y601952I-4368J-2112D01*
G02X157246Y602632I-41J398D01*
G01X160400Y605787D01*
Y639357D01*
X160702Y639658D01*
Y652364D01*
G02X161384Y652647I400J0D01*
G01X163198Y650833D01*
Y599413D01*
G02X162438Y599238I-400J-1D01*
G37*
G36*
G01X151219Y1079503D02*
X190316Y1118601D01*
X190228Y1118689D01*
X190319Y1118826D01*
G03X190613Y1119298I-6785J4554D01*
G02X191360Y1119099I347J-199D01*
G01Y1101188D01*
X169399Y1079228D01*
X163476D01*
X161322Y1077073D01*
Y1071150D01*
X159461Y1069290D01*
X145600D01*
Y1077342D01*
X146001D01*
G03X151219Y1079503I0J7381D01*
G37*
G36*
G01X168248Y1075566D02*
X164983Y1072301D01*
G02X164300Y1072584I-283J283D01*
G01Y1075839D01*
X164710Y1076248D01*
X167965D01*
G02X168248Y1075566I0J-400D01*
G37*
G36*
G01X122124Y1081419D02*
G03X119002Y1080020I275J-4797D01*
G01X116283Y1077300D01*
G02X115600Y1077583I-283J283D01*
G01Y1082826D01*
X116773Y1083998D01*
X123169D01*
X123356Y1083811D01*
G02X123272Y1083182I-283J-282D01*
G03X122124Y1081419I1151J-2005D01*
G37*
G36*
G01X551352Y1841670D02*
X907218Y1485805D01*
Y1485644D01*
G02X906535Y1485361I-400J0D01*
G01X871600Y1520295D01*
Y1520660D01*
X551987Y1840274D01*
X155900D01*
Y1841670D01*
X551352D01*
G37*
G36*
G01X287301Y338651D02*
G03X284898Y340950I-2302J-1D01*
G01X284810Y340946D01*
X246891Y378865D01*
G02X247174Y379547I283J282D01*
G01X348597D01*
G02X348880Y378865I0J-400D01*
G01X308267Y338252D01*
X287701D01*
G02X287301Y338651I0J400D01*
G37*
G36*
G01X186600Y792640D02*
Y794019D01*
X189192Y796610D01*
X306826D01*
X310114Y793322D01*
G02X309831Y792640I-283J-282D01*
G01X186600D01*
G37*
G36*
G01X322798Y797940D02*
G03X318744Y799540I-2299J110D01*
G01X310621D01*
X307333Y802828D01*
X186600D01*
Y806660D01*
X339940Y960000D01*
X343000D01*
X344010Y958990D01*
Y815316D01*
X331780Y803086D01*
G02X331201Y803100I-283J283D01*
G03X327199Y801449I-1702J-1550D01*
G01X327203Y801361D01*
X323481Y797638D01*
G02X322798Y797940I-283J283D01*
G37*
G36*
G01X335884Y963948D02*
X211605Y839668D01*
G02X211013Y839698I-282J283D01*
G03X210909Y839817I-2010J-1652D01*
G02X210907Y840358I294J272D01*
G03X210932Y843840I-1921J1755D01*
G02X210934Y844373I300J265D01*
G03X207047Y847833I-1934J1740D01*
G02X206447Y847832I-300J264D01*
G03X202624Y844304I-1951J-1721D01*
G02X202644Y843771I-288J-278D01*
G03X202733Y840352I2005J-1658D01*
G02Y839811I-294J-270D01*
G03X206534Y836257I1916J-1761D01*
G02X207114I290J-276D01*
G03X207351Y836036I1890J1789D01*
G02X207381Y835444I-253J-310D01*
G01X187283Y815346D01*
G02X186600Y815629I-283J283D01*
G01Y821100D01*
X180053Y827647D01*
X314162Y961756D01*
Y1064532D01*
X340330Y1090700D01*
X342122D01*
Y1061279D01*
X335884Y1055042D01*
Y963948D01*
G37*
G36*
G01X325617Y1627580D02*
X188932Y1764266D01*
G02X189215Y1764948I283J282D01*
G01X298944D01*
X340796Y1723096D01*
X326300Y1708600D01*
Y1627863D01*
G02X325617Y1627580I-400J0D01*
G37*
G36*
G01X348580Y407315D02*
G02X347898Y407598I-282J283D01*
G01Y595734D01*
G02X348623Y595965I400J-1D01*
G03Y598635I1876J1335D01*
G02X347898Y598866I-325J232D01*
G01Y684758D01*
X287795Y744861D01*
X287799Y744949D01*
G03X283935Y746739I-2300J101D01*
G02X283663I-136J147D01*
G03X283588Y746805I-1558J-1695D01*
G01Y760627D01*
X288393Y765432D01*
G02X288985Y765402I282J-283D01*
G03X289276Y765100I2013J1649D01*
G02Y764500I-264J-300D01*
G03Y760600I1723J-1950D01*
G02Y760000I-264J-300D01*
G03X292733Y756110I1723J-1950D01*
G02X293265I266J-299D01*
G03X296722Y760000I1734J1940D01*
G02Y760600I264J300D01*
G03Y764500I-1723J1950D01*
G02Y765100I264J300D01*
G03X293265Y768990I-1723J1950D01*
G02X292733I-266J299D01*
G03X292647Y769064I-1740J-1935D01*
G02X292617Y769656I253J310D01*
G01X294872Y771910D01*
X324273D01*
X355991Y803628D01*
G02X356674Y803345I283J-283D01*
G01Y775081D01*
X327938Y746346D01*
X327850Y746350D01*
G03X326227Y742323I-101J-2300D01*
G02X326247Y742043I-132J-150D01*
G03X330299Y740651I1752J-1493D01*
G01X330295Y740739D01*
X359785Y770229D01*
G02X360468Y769946I283J-283D01*
G01Y727125D01*
X350688Y717346D01*
X350600Y717350D01*
G03X352799Y715151I-101J-2300D01*
G01X352795Y715239D01*
X360517Y722962D01*
G02X361200Y722679I283J-283D01*
G01Y419934D01*
X348580Y407315D01*
G37*
G36*
G01X334817Y1268044D02*
X332650Y1270211D01*
Y1300800D01*
X335500D01*
Y1268327D01*
G02X334817Y1268044I-400J0D01*
G37*
G36*
G01X344502Y1776610D02*
X380930Y1740183D01*
G02X380647Y1739500I-283J-283D01*
G01X369652D01*
Y1743004D01*
X350795Y1761861D01*
X350799Y1761949D01*
G03X348600Y1759750I-2300J101D01*
G01X348688Y1759754D01*
X366672Y1741770D01*
Y1738872D01*
X361200Y1733400D01*
Y1727966D01*
G02X360517Y1727683I-400J0D01*
G01X356300Y1731900D01*
X349600D01*
X346669Y1728969D01*
X299721Y1775917D01*
G02X300004Y1776600I283J283D01*
G01X344000D01*
X344011Y1776610D01*
X344502D01*
G37*
G36*
G01X867464Y1514535D02*
X546944Y1835056D01*
X546900Y1835123D01*
X546894Y1835136D01*
G03X546849Y1835221I-1338J-654D01*
G02X547023Y1835520I174J99D01*
G01X550017D01*
X866846Y1518690D01*
Y1518325D01*
X903668Y1481504D01*
Y1479297D01*
G02X902985Y1479014I-400J0D01*
G01X868655Y1513343D01*
X867464Y1514533D01*
Y1514535D01*
G37*
G36*
G01X775467Y1163316D02*
G03X777783Y1164169I366J2576D01*
G02X778383I300J-264D01*
G03X780481Y1163294I1950J1723D01*
G02X780880Y1162761I22J-399D01*
G03X781610Y1159942I2453J-869D01*
G02Y1159342I-264J-300D01*
G03X785056I1723J-1950D01*
G02Y1159942I264J300D01*
G03X783185Y1164490I-1723J1950D01*
G02X782786Y1165023I-22J399D01*
G03X778383Y1167615I-2453J869D01*
G02X777783I-300J264D01*
G03X775467Y1168468I-1950J-1723D01*
G02X775010Y1168864I-57J396D01*
G01Y1342452D01*
X863980Y1431421D01*
Y1435548D01*
X864098Y1435666D01*
Y1498548D01*
G03X864094Y1498607I-400J2D01*
G02X864372Y1499049I395J60D01*
G03X864065Y1503523I-673J2201D01*
G01X863897Y1503550D01*
Y1509308D01*
X863300Y1509904D01*
Y1511008D01*
G02X863983Y1511290I400J-1D01*
G01X867132Y1508143D01*
X900118Y1475157D01*
Y1400530D01*
G02X899553Y1400166I-400J1D01*
G03X897821Y1400540I-1733J-3827D01*
G01X893519D01*
G03Y1392138I0J-4201D01*
G01X897821D01*
G03X899553Y1392512I-1J4201D01*
G02X900118Y1392148I165J-365D01*
G01Y1168246D01*
G02X899553Y1167882I-400J1D01*
G03X897821Y1168256I-1733J-3827D01*
G01X893519D01*
G03Y1159854I0J-4201D01*
G01X897821D01*
G03X899553Y1160228I-1J4201D01*
G02X900118Y1159864I165J-365D01*
G01Y1122503D01*
X856820Y1079206D01*
X854088D01*
G03Y1076226I-1755J-1490D01*
G01X858054D01*
X901210Y1119382D01*
G02X901892Y1119099I282J-283D01*
G01Y993598D01*
G02X901173Y993357I-400J0D01*
G03X897819Y995028I-3354J-2531D01*
G01X893519D01*
G03Y986626I0J-4201D01*
G01X897819D01*
G03X901173Y988297I0J4202D01*
G02X901892Y988056I319J-241D01*
G01Y981705D01*
G02X901419Y981313I-400J1D01*
G03Y976787I-420J-2263D01*
G02X901892Y976395I73J-393D01*
G01Y964612D01*
G02X901345Y964241I-400J1D01*
G03X898744Y963590I-846J-2141D01*
G01X897717D01*
X884504Y976803D01*
G02X884534Y977396I283J283D01*
G03X881296Y980634I-1451J1787D01*
G02X880703Y980604I-310J253D01*
G01X780988Y1080318D01*
Y1129295D01*
G03X780872Y1132898I-1489J1755D01*
G02X780827Y1133502I238J321D01*
G01X784274Y1136948D01*
X787478D01*
G03X789665Y1135754I2021J1102D01*
G02X789878Y1135584I15J-200D01*
G03X791988Y1138222I2276J342D01*
G02X791775Y1138392I-15J200D01*
G03X788167Y1139928I-2276J-342D01*
G01X783040D01*
X775693Y1132581D01*
G02X775010Y1132863I-283J283D01*
G01Y1162920D01*
G02X775467Y1163316I400J0D01*
G37*
G36*
G01X864281Y1535465D02*
X826057Y1573690D01*
G02X826340Y1574372I283J282D01*
G01X828737D01*
X865671Y1537438D01*
G02X865656Y1536859I-283J-282D01*
G03X864954Y1535660I1543J-1709D01*
G02X864281Y1535465I-390J88D01*
G37*
G36*
G01X910085Y1489662D02*
X867514Y1532232D01*
G02X867709Y1532905I283J283D01*
G03X868908Y1533607I-510J2245D01*
G02X869487Y1533622I297J-268D01*
G01X910768Y1492342D01*
Y1489945D01*
G02X910085Y1489662I-400J0D01*
G37*
%LPC*%
G75*
G36*
G01X135003Y1979810D02*
G03X135696Y1979783I354J186D01*
G02X135597Y1977190I2204J-1383D01*
G03X134904Y1977217I-354J-186D01*
G02X135003Y1979810I-2204J1383D01*
G37*
G36*
G01X774074Y1973765D02*
G03X773541Y1973767I-268J-298D01*
G02X773554Y1977647I-1727J1946D01*
G03X774087Y1977645I268J298D01*
G02X774074Y1973765I1727J-1946D01*
G37*
G36*
G01X135003Y1973610D02*
G03X135696Y1973583I354J186D01*
G02X135597Y1970990I2204J-1383D01*
G03X134904Y1971017I-354J-186D01*
G02X135003Y1973610I-2204J1383D01*
G37*
G36*
G01X782091Y1969163D02*
G03Y1969763I-264J300D01*
G02X781964Y1973542I1723J1950D01*
G03X781991Y1974075I-285J282D01*
G02X785866Y1973879I2025J1633D01*
G03X785839Y1973346I285J-282D01*
G02X785537Y1969763I-2025J-1634D01*
G03Y1969163I264J-300D01*
G02X782091I-1723J-1950D01*
G37*
G36*
G01X344371Y1945560D02*
G03X344315Y1944968I238J-321D01*
G02X341249Y1945258I-1694J-1559D01*
G03X341305Y1945850I-238J321D01*
G02X344371Y1945560I1694J1559D01*
G37*
G36*
G01X100721Y1938595D02*
G03X100188Y1938589I-263J-301D01*
G02X96788Y1942526I-1755J1921D01*
G03X96863Y1943064I-253J310D01*
G02X100936Y1946287I2136J1486D01*
G03X101527Y1946282I298J267D01*
G02X104850Y1942328I1906J-1772D01*
G03X104717Y1941801I218J-335D01*
G02X100721Y1938595I-2284J-1246D01*
G37*
G36*
G01X296360Y1931068D02*
G03X295761Y1931135I-329J-228D01*
G02X296138Y1934532I-1762J1915D01*
G03X296737Y1934465I329J228D01*
G02X300233Y1934490I1762J-1915D01*
G03X300765I266J299D01*
G02X304449Y1934273I1734J-1940D01*
G03X305049I300J264D01*
G02Y1930827I1950J-1723D01*
G03X304449I-300J-264D01*
G02X300765Y1930610I-1950J1723D01*
G03X300233I-266J-299D01*
G02X296360Y1931068I-1734J1940D01*
G37*
G36*
G01X25133Y1920322D02*
G03X24580Y1920336I-284J-282D01*
G02X24662Y1923661I-1550J1702D01*
G03X25215Y1923647I284J282D01*
G02X25133Y1920322I1550J-1702D01*
G37*
G36*
G01X280559Y1925717D02*
G03Y1926383I-222J333D01*
G02X282972Y1930963I1441J2167D01*
G03X283474Y1931144I150J371D01*
G02X284894Y1927829I2025J-1094D01*
G03X284418Y1927590I-104J-386D01*
G02X283439Y1926383I-2418J961D01*
G03Y1925717I222J-333D01*
G02Y1921383I-1440J-2167D01*
G03Y1920717I222J-333D01*
G02X280559I-1440J-2167D01*
G03Y1921383I-222J333D01*
G02Y1925717I1440J2167D01*
G37*
G36*
G01X809659Y1912915D02*
G03Y1912315I264J-300D01*
G02X806213I-1723J-1950D01*
G03Y1912915I-264J300D01*
G02X806026Y1916632I1723J1950D01*
G03X806035Y1917165I-294J272D01*
G02X806061Y1920595I1970J1700D01*
G03X806060Y1921128I-299J266D01*
G02X809941Y1921135I1937J1737D01*
G03X809942Y1920602I299J-266D01*
G02X809915Y1917098I-1937J-1737D01*
G03X809906Y1916565I294J-272D01*
G02X809659Y1912915I-1970J-1700D01*
G37*
G36*
G01X793709Y1919582D02*
G03X793708Y1920162I-276J290D01*
G02X797291Y1920164I1790J1888D01*
G03X797292Y1919584I276J-290D01*
G02X797438Y1915959I-1791J-1888D01*
G03X797437Y1915426I298J-267D01*
G02X797448Y1911978I-1944J-1730D01*
G03X797452Y1911446I300J-264D01*
G02X793571Y1911414I-1926J-1750D01*
G03X793567Y1911946I-300J264D01*
G02X793556Y1915433I1926J1750D01*
G03X793557Y1915966I-298J267D01*
G02X793709Y1919582I1944J1729D01*
G37*
G36*
G01X131994Y1911381D02*
G03X132194Y1910861I368J-157D01*
G02X128706Y1909519I-1094J-2361D01*
G03X128506Y1910039I-368J157D01*
G02X127552Y1910796I1095J2360D01*
G03X126939Y1910815I-314J-247D01*
G02X126644Y1910534I-1937J1738D01*
G03X126569Y1909996I253J-310D01*
G02X122788Y1910526I-2136J-1486D01*
G03X122863Y1911064I-253J310D01*
G02X127047Y1914154I2136J1486D01*
G03X127660Y1914135I314J247D01*
G02X131994Y1911381I1940J-1734D01*
G37*
G36*
G01X76833Y1897492D02*
G03X76757Y1898019I-333J221D01*
G02X76788Y1902026I1676J1991D01*
G03X76863Y1902564I-253J310D01*
G02X80936Y1905787I2136J1486D01*
G03X81527Y1905782I298J267D01*
G02X85599Y1902568I1907J-1771D01*
G03X85675Y1902041I333J-221D01*
G02X85696Y1898077I-1676J-1991D01*
G03X85629Y1897544I260J-303D01*
G02X84981Y1893911I-2130J-1494D01*
G03X84914Y1893312I228J-329D01*
G02X84939Y1889816I-1915J-1762D01*
G03Y1889284I299J-266D01*
G02X81265Y1885610I-1940J-1734D01*
G03X80733I-266J-299D01*
G02X77059Y1889284I-1734J1940D01*
G03Y1889816I-299J266D01*
G02X77276Y1893500I1940J1734D01*
G03Y1894100I-264J300D01*
G02X76833Y1897492I1723J1950D01*
G37*
G36*
G01X855810Y1871046D02*
Y1870948D01*
X855804Y1870860D01*
G02X853485Y1868725I-2305J176D01*
G01X850085Y1868745D01*
G02X850113Y1873367I14J2311D01*
G01X853512Y1873347D01*
G02X855810Y1871046I-13J-2311D01*
G37*
G36*
G01X869226Y1865625D02*
Y1861752D01*
X869219Y1861664D01*
G02X864602Y1861840I-2305J176D01*
G01Y1865615D01*
G02X869226Y1865625I2312J0D01*
G37*
G36*
G01X805299Y1824144D02*
G03X805579Y1824111I157J124D01*
G02X805201Y1820864I1421J-1811D01*
G03X804921Y1820897I-157J-124D01*
G02X805299Y1824144I-1421J1811D01*
G37*
G36*
G01X713444Y1823845D02*
G03X713428Y1823573I138J-145D01*
G02X710056Y1823768I-1776J-1464D01*
G03X710072Y1824040I-138J145D01*
G02X713444Y1823845I1776J1464D01*
G37*
G36*
G01X643642Y1816423D02*
G03X643466Y1817016I-331J224D01*
G02X646267Y1817848I894J2121D01*
G03X646443Y1817255I331J-224D01*
G02X643642Y1816423I-894J-2121D01*
G37*
G36*
G01X795489Y1803226D02*
G03X795261Y1803067I-32J-197D01*
G02X793360Y1805774I-2261J433D01*
G03X793588Y1805933I32J197D01*
G02X795489Y1803226I2261J-433D01*
G37*
G36*
G01X884196Y1746470D02*
G03X884755Y1746416I307J256D01*
G02X884404Y1742730I1645J-2016D01*
G03X883845Y1742784I-307J-256D01*
G02X884196Y1746470I-1645J2016D01*
G37*
G36*
G01X979460Y1661707D02*
G03X979724Y1661635I170J105D01*
G02X978840Y1658393I1076J-2035D01*
G03X978576Y1658465I-170J-105D01*
G02X979460Y1661707I-1076J2035D01*
G37*
G36*
G01X980172Y1650633D02*
G03X980090Y1651180I-327J231D01*
G02X983378Y1651669I1410J1820D01*
G03X983460Y1651122I327J-231D01*
G02X980172Y1650633I-1410J-1820D01*
G37*
G36*
G01X963658Y1636924D02*
G03X963199Y1636509I-59J-396D01*
G02X961242Y1638676I-2299J-109D01*
G03X961701Y1639091I59J396D01*
G02X963658Y1636924I2299J109D01*
G37*
G36*
G01X752940Y1519266D02*
G03Y1518734I299J-266D01*
G02X749060I-1940J-1734D01*
G03Y1519266I-299J266D01*
G02Y1522734I1940J1734D01*
G03Y1523266I-299J266D01*
G02X752940I1940J1734D01*
G03Y1522734I299J-266D01*
G02Y1519266I-1940J-1734D01*
G37*
G36*
G01X797439Y1507383D02*
G03Y1506717I222J-333D01*
G02X794559I-1440J-2167D01*
G03Y1507383I-222J333D01*
G02X794276Y1511500I1440J2167D01*
G03Y1512100I-264J300D01*
G02Y1516000I1723J1950D01*
G03Y1516600I-264J300D01*
G02X797722I1723J1950D01*
G03Y1516000I264J-300D01*
G02Y1512100I-1723J-1950D01*
G03Y1511500I264J-300D01*
G02X797439Y1507383I-1723J-1950D01*
G37*
G36*
G01X807805Y1505889D02*
G03Y1506555I-222J333D01*
G02X807597Y1510736I1440J2167D01*
G03X807565Y1511379I-253J310D01*
G02X807790Y1515854I1434J2171D01*
G03X807823Y1516543I-186J354D01*
G02X810454Y1516418I1422J2179D01*
G03X810421Y1515729I186J-354D01*
G02X810647Y1511536I-1422J-2179D01*
G03X810679Y1510893I253J-310D01*
G02X810685Y1506555I-1434J-2171D01*
G03Y1505889I222J-333D01*
G02X807805I-1440J-2167D01*
G37*
G36*
G01X974053Y1500177D02*
G03X974073Y1499510I231J-327D01*
G02X971196Y1499423I-1373J-2210D01*
G03X971176Y1500090I-231J327D01*
G02X970826Y1504250I1373J2210D01*
G03Y1504850I-264J300D01*
G02X974272I1723J1950D01*
G03Y1504250I264J-300D01*
G02X974053Y1500177I-1723J-1950D01*
G37*
G36*
G01X961553Y1498177D02*
G03X961573Y1497510I231J-327D01*
G02X958696Y1497423I-1373J-2210D01*
G03X958676Y1498090I-231J327D01*
G02X958326Y1502250I1373J2210D01*
G03Y1502850I-264J300D01*
G02X961772I1723J1950D01*
G03Y1502250I264J-300D01*
G02X961553Y1498177I-1723J-1950D01*
G37*
G36*
G01X949996Y1497423D02*
G03X949976Y1498090I-231J327D01*
G02X949626Y1502250I1373J2210D01*
G03Y1502850I-264J300D01*
G02X953072I1723J1950D01*
G03Y1502250I264J-300D01*
G02X952853Y1498177I-1723J-1950D01*
G03X952873Y1497510I231J-327D01*
G02X949996Y1497423I-1373J-2210D01*
G37*
G36*
G01X854600Y1466356D02*
Y1466258D01*
X854593Y1466170D01*
G02X852250Y1464035I-2305J176D01*
G01X848851Y1464091D01*
G02X848926Y1468713I38J2311D01*
G01X852326Y1468657D01*
G02X854600Y1466356I-38J-2311D01*
G37*
G36*
G01X970317Y1464504D02*
G03X970290Y1465197I-213J339D01*
G02X972883Y1465296I1210J2303D01*
G03X972910Y1464603I213J-339D01*
G02X973423Y1460350I-1210J-2303D01*
G03Y1459750I264J-300D01*
G02X973140Y1455633I-1723J-1950D01*
G03Y1454967I222J-333D01*
G02X973423Y1450850I-1440J-2167D01*
G03Y1450250I264J-300D01*
G02X969977I-1723J-1950D01*
G03Y1450850I-264J300D01*
G02X970260Y1454967I1723J1950D01*
G03Y1455633I-222J333D01*
G02X969977Y1459750I1440J2167D01*
G03Y1460350I-264J300D01*
G02X970317Y1464504I1723J1950D01*
G37*
G36*
G01X951117D02*
G03X951090Y1465197I-213J339D01*
G02X953683Y1465296I1210J2303D01*
G03X953710Y1464603I213J-339D01*
G02X954223Y1460350I-1210J-2303D01*
G03Y1459750I264J-300D01*
G02X953940Y1455633I-1723J-1950D01*
G03Y1454967I222J-333D01*
G02X954223Y1450850I-1440J-2167D01*
G03Y1450250I264J-300D01*
G02X950777I-1723J-1950D01*
G03Y1450850I-264J300D01*
G02X951060Y1454967I1723J1950D01*
G03Y1455633I-222J333D01*
G02X950777Y1459750I1440J2167D01*
G03Y1460350I-264J300D01*
G02X951117Y1464504I1723J1950D01*
G37*
G36*
G01X960817Y1463504D02*
G03X960790Y1464197I-213J339D01*
G02X963383Y1464296I1210J2303D01*
G03X963410Y1463603I213J-339D01*
G02X963923Y1459350I-1210J-2303D01*
G03Y1458750I264J-300D01*
G02X963640Y1454633I-1723J-1950D01*
G03Y1453967I222J-333D01*
G02X963923Y1449850I-1440J-2167D01*
G03Y1449250I264J-300D01*
G02X960477I-1723J-1950D01*
G03Y1449850I-264J300D01*
G02X960760Y1453967I1723J1950D01*
G03Y1454633I-222J333D01*
G02X960477Y1458750I1440J2167D01*
G03Y1459350I-264J300D01*
G02X960817Y1463504I1723J1950D01*
G37*
G36*
G01X973723Y1440050D02*
G03Y1439450I264J-300D01*
G02X970277I-1723J-1950D01*
G03Y1440050I-264J300D01*
G02X973723I1723J1950D01*
G37*
G36*
G01X954523D02*
G03Y1439450I264J-300D01*
G02X951077I-1723J-1950D01*
G03Y1440050I-264J300D01*
G02X954523I1723J1950D01*
G37*
G36*
G01X964223Y1439050D02*
G03Y1438450I264J-300D01*
G02X960777I-1723J-1950D01*
G03Y1439050I-264J300D01*
G02X964223I1723J1950D01*
G37*
G36*
G01X747737Y714135D02*
G03X747138Y714068I-270J-295D01*
G02X743517Y717689I-2139J1482D01*
G03X743584Y718288I-228J329D01*
G02X747449Y721773I1915J1762D01*
G03X748049I300J264D01*
G02X751696Y718077I1949J-1724D01*
G03X751629Y717544I260J-303D01*
G02X747737Y714135I-2130J-1494D01*
G37*
G36*
G01X796054Y700903D02*
G03Y700303I264J-300D01*
G02X792608I-1723J-1950D01*
G03Y700903I-264J300D01*
G02Y704803I1723J1950D01*
G03Y705403I-264J300D01*
G02Y709303I1723J1950D01*
G03Y709903I-264J300D01*
G02X796054I1723J1950D01*
G03Y709303I264J-300D01*
G02Y705403I-1723J-1950D01*
G03Y704803I264J-300D01*
G02Y700903I-1723J-1950D01*
G37*
G36*
G01X808462Y699826D02*
G03X808485Y699186I251J-311D01*
G02X805368Y699077I-1486J-2136D01*
G03X805345Y699717I-251J311D01*
G02X805391Y704020I1486J2136D01*
G03Y704686I-222J333D01*
G02Y709020I1440J2167D01*
G03Y709686I-222J333D01*
G02X808271I1440J2167D01*
G03Y709020I222J-333D01*
G02Y704686I-1440J-2167D01*
G03Y704020I222J-333D01*
G02X808462Y699826I-1440J-2167D01*
G37*
G36*
G01X851214Y653121D02*
X847814Y653059D01*
G02X847730Y657681I-42J2311D01*
G01X851129Y657743D01*
G02X853480Y655560I43J-2311D01*
G01X853482Y655522D01*
X853483Y655483D01*
G02Y655382I-2311J-51D01*
G01X853482Y655380D01*
Y655370D01*
G02X851214Y653121I-2310J62D01*
G37*
G36*
G01X880908Y649358D02*
Y645485D01*
X880901Y645397D01*
G02X876284Y645573I-2305J176D01*
G01Y649348D01*
G02X880908Y649358I2312J0D01*
G37*
G36*
G01X556774Y614102D02*
G03X556215Y614074I-265J-299D01*
G02X552537Y617750I-1911J1766D01*
G03X552563Y618311I-271J294D01*
G02X552776Y622000I1936J1739D01*
G03Y622600I-264J300D01*
G02X556319Y626409I1723J1950D01*
G03X556879I280J286D01*
G02X560517Y622689I1820J-1859D01*
G03X560518Y622115I279J-287D01*
G02X560475Y618334I-1809J-1870D01*
G03X560447Y617775I271J-294D01*
G02X556774Y614102I-1948J-1725D01*
G37*
G36*
G01X781690Y722850D02*
Y662207D01*
X877507Y566390D01*
G03X878109Y566432I283J283D01*
G02X881332Y563209I1841J-1382D01*
G03X881290Y562607I241J-319D01*
G01X886357Y557540D01*
X901244D01*
G02Y554560I1755J-1490D01*
G01X885123D01*
X778710Y660973D01*
Y724368D01*
X779703Y725361D01*
X779699Y725449D01*
G02X782076Y723249I2300J101D01*
G03X781690Y722850I14J-399D01*
G37*
G36*
G01X28610Y403386D02*
Y399513D01*
X28604Y399425D01*
G02X23988Y399601I-2305J176D01*
G01Y403376D01*
G02X28610Y403386I2311J0D01*
G37*
G36*
G01Y387639D02*
Y383766D01*
X28604Y383678D01*
G02X23988Y383854I-2305J176D01*
G01Y387629D01*
G02X28610Y387639I2311J0D01*
G37*
G36*
G01X559939Y324816D02*
G03Y324284I299J-266D01*
G02X556059I-1940J-1734D01*
G03Y324816I-299J266D01*
G02X556229Y328457I1940J1734D01*
G03X556220Y329051I-272J293D01*
G02X556083Y332840I1713J1959D01*
G03X556105Y333378I-284J281D01*
G02X559949Y333220I1994J1672D01*
G03X559927Y332682I284J-281D01*
G02X559703Y329103I-1994J-1672D01*
G03X559712Y328509I272J-293D01*
G02X559939Y324816I-1713J-1959D01*
G37*
G36*
G01X754057Y312384D02*
G03X753530Y312308I-221J-333D01*
G02X749607Y315727I-1991J1676D01*
G03X749602Y316269I-297J268D01*
G02X752633Y320392I1897J1781D01*
G03X753146Y320538I175J360D01*
G02X757083Y317211I2200J-1390D01*
G03X757103Y316599I267J-298D01*
G02X754057Y312384I-1603J-2050D01*
G37*
G36*
G01X281721Y297664D02*
G03Y297064I264J-300D01*
G02X278275I-1723J-1950D01*
G03Y297664I-264J300D01*
G02Y301564I1723J1950D01*
G03Y302164I-264J300D01*
G02Y306064I1723J1950D01*
G03Y306664I-264J300D01*
G02X281721I1723J1950D01*
G03Y306064I264J-300D01*
G02Y302164I-1723J-1950D01*
G03Y301564I264J-300D01*
G02Y297664I-1723J-1950D01*
G37*
G36*
G01X268938Y297947D02*
G03Y297281I222J-333D01*
G02X266058I-1440J-2167D01*
G03Y297947I-222J333D01*
G02Y302281I1440J2167D01*
G03Y302947I-222J333D01*
G02Y307281I1440J2167D01*
G03Y307947I-222J333D01*
G02X268938I1440J2167D01*
G03Y307281I222J-333D01*
G02Y302947I-1440J-2167D01*
G03Y302281I222J-333D01*
G02Y297947I-1440J-2167D01*
G37*
G36*
G01X853590Y249984D02*
Y249886D01*
X853583Y249798D01*
G02X851233Y247663I-2305J176D01*
G01X847834Y247729D01*
G02X847923Y252351I44J2311D01*
G01X851323Y252285D01*
G02X853590Y249984I-45J-2311D01*
G37*
G36*
G01X125110Y249160D02*
Y249062D01*
X125104Y248974D01*
G02X120530Y248708I-2305J175D01*
G01X120496Y248887D01*
X120493Y248886D01*
X120090Y252426D01*
X120098Y252433D01*
X120092Y252524D01*
G02X124666Y253130I2305J164D01*
G01X124700Y252951D01*
X124703Y252952D01*
X124722Y252787D01*
X125106Y249411D01*
X125103Y249410D01*
X125109Y249224D01*
G02X125110Y249184I-2310J-78D01*
G01Y249160D01*
G37*
G36*
G01X880390Y243888D02*
Y240015D01*
X880383Y239927D01*
G02X875766Y240103I-2305J176D01*
G01Y243878D01*
G02X880390Y243888I2312J0D01*
G37*
G36*
G01X152310Y243514D02*
Y239641D01*
X152304Y239553D01*
G02X147688Y239729I-2305J176D01*
G01Y243504D01*
G02X152310Y243514I2311J0D01*
G37*
G36*
G01X831817Y217500D02*
G03X832359Y217386I330J225D01*
G02X831676Y214132I1217J-1954D01*
G03X831134Y214246I-330J-225D01*
G02X831817Y217500I-1217J1954D01*
G37*
G36*
G01X226365Y189075D02*
G03X226299Y189741I-251J311D01*
G02X229449Y193773I1200J2309D01*
G03X230049I300J264D01*
G02X233439Y189883I1950J-1723D01*
G03Y189217I222J-333D01*
G02X233722Y185100I-1440J-2167D01*
G03Y184500I264J-300D01*
G02Y180600I-1723J-1950D01*
G03Y180000I264J-300D01*
G02X230265Y176110I-1723J-1950D01*
G03X229733I-266J-299D01*
G02X226276Y180000I-1734J1940D01*
G03Y180600I-264J300D01*
G02Y184500I1723J1950D01*
G03Y185100I-264J300D01*
G02X226365Y189075I1723J1950D01*
G37*
G36*
G01X869080Y162249D02*
G03X869091Y161657I274J-291D01*
G02X865996Y161599I-1516J-1733D01*
G03X865985Y162191I-274J291D01*
G02X869080Y162249I1516J1733D01*
G37*
G36*
G01X756265Y152610D02*
G03X755733I-266J-299D01*
G02X752276Y156500I-1734J1940D01*
G03Y157100I-264J300D01*
G02X755733Y160990I1723J1950D01*
G03X756265I266J299D01*
G02X759722Y157100I1734J-1940D01*
G03Y156500I264J-300D01*
G02X756265Y152610I-1723J-1950D01*
G37*
G36*
G01X34798Y135039D02*
G03X34171Y135025I-308J-256D01*
G02X34102Y138261I-2071J1575D01*
G03X34729Y138275I308J256D01*
G02X34798Y135039I2071J-1575D01*
G37*
G36*
G01X34224Y132204D02*
G03X34876I326J231D01*
G02Y129196I2124J-1504D01*
G03X34224I-326J-231D01*
G02Y132204I-2124J1504D01*
G37*
G36*
G01X88904Y126579D02*
X88903Y126569D01*
G02X84295Y126931I-2304J181D01*
G01X84595Y130747D01*
G02X89210Y130577I2304J-180D01*
G01Y130567D01*
X89211D01*
G02Y130564I-2312J-2D01*
G01X89210D01*
Y130478D01*
X89204Y130391D01*
G02X89203Y130386I-2267J451D01*
G01X88904Y126579D01*
G37*
G36*
G01X117988Y129132D02*
Y126891D01*
X118003Y126854D01*
G02X113749I-2127J-881D01*
G01X113764Y126891D01*
Y129132D01*
X113749Y129169D01*
G02X118003I2127J881D01*
G01X117988Y129132D01*
G37*
G36*
G01X350049Y111327D02*
G03X349449I-300J-264D01*
G02Y114773I-1950J1723D01*
G03X350049I300J264D01*
G02X353949I1950J-1723D01*
G03X354549I300J264D01*
G02X358449I1950J-1723D01*
G03X359049I300J264D01*
G02Y111327I1950J-1723D01*
G03X358449I-300J-264D01*
G02X354549I-1950J1723D01*
G03X353949I-300J-264D01*
G02X350049I-1950J1723D01*
G37*
G36*
G01X900889Y108905D02*
G03X900609I-140J-143D01*
G02Y112195I-1610J1645D01*
G03X900889I140J143D01*
G02Y108905I1610J-1645D01*
G37*
G36*
G01X889017Y97950D02*
G03X888490Y97874I-221J-333D01*
G02X885059Y101717I-1990J1676D01*
G03Y102383I-222J333D01*
G02X888233Y106490I1440J2167D01*
G03X888765I266J299D01*
G02X892236Y102613I1734J-1940D01*
G03X892231Y102022I267J-298D01*
G02X889017Y97950I-1771J-1907D01*
G37*
G36*
G01X900343Y90059D02*
G03X899759Y89829I-201J-346D01*
G02X898711Y92485I-2204J665D01*
G03X899295Y92715I201J346D01*
G02X900343Y90059I2204J-665D01*
G37*
G36*
G01X281310Y89255D02*
Y92632D01*
X231382Y142560D01*
X116741D01*
X98988Y124808D01*
Y91805D01*
G02X96010I-1489J-1755D01*
G01Y126042D01*
X115507Y145540D01*
X232616D01*
X284290Y93866D01*
Y89255D01*
G02X281310I-1490J-1755D01*
G37*
G36*
G01X841600Y85137D02*
G03X842199Y84804I400J14D01*
G02X840898Y82463I1300J-2254D01*
G03X840299Y82796I-400J-14D01*
G02X841600Y85137I-1300J2254D01*
G37*
G36*
G01X177295Y77502D02*
G03X176703I-296J-269D01*
G02Y80598I-1704J1548D01*
G03X177295I296J269D01*
G02Y77502I1704J-1548D01*
G37*
G36*
G01X168222Y81600D02*
G03Y81000I264J-300D01*
G02X164776I-1723J-1950D01*
G03Y81600I-264J300D01*
G02X165017Y85689I1723J1950D01*
G03X165084Y86288I-228J329D01*
G02X165276Y90000I1915J1762D01*
G03Y90600I-264J300D01*
G02Y94500I1723J1950D01*
G03Y95100I-264J300D01*
G02X168722I1723J1950D01*
G03Y94500I264J-300D01*
G02Y90600I-1723J-1950D01*
G03Y90000I264J-300D01*
G02X168481Y85911I-1723J-1950D01*
G03X168414Y85312I228J-329D01*
G02X168222Y81600I-1915J-1762D01*
G37*
G36*
G01X159939Y81883D02*
G03Y81217I222J-333D01*
G02X157059I-1440J-2167D01*
G03Y81883I-222J333D01*
G02X156776Y86000I1440J2167D01*
G03Y86600I-264J300D01*
G02X157059Y90717I1723J1950D01*
G03Y91383I-222J333D01*
G02X159939I1440J2167D01*
G03Y90717I222J-333D01*
G02X160222Y86600I-1440J-2167D01*
G03Y86000I264J-300D01*
G02X159939Y81883I-1723J-1950D01*
G37*
G36*
G01X379549Y63827D02*
G03X378949I-300J-264D01*
G02X375276Y67500I-1950J1723D01*
G03Y68100I-264J300D01*
G02X378949Y71773I1723J1950D01*
G03X379549I300J264D01*
G02X383222Y68100I1950J-1723D01*
G03Y67500I264J-300D01*
G02X379549Y63827I-1723J-1950D01*
G37*
G36*
G01X944439Y64383D02*
G03Y63717I222J-333D01*
G02X941559I-1440J-2167D01*
G03Y64383I-222J333D01*
G02X944439I1440J2167D01*
G37*
G36*
G01X906633Y59525D02*
G03X906699Y58859I251J-311D01*
G02X903865Y58575I-1200J-2309D01*
G03X903799Y59241I-251J311D01*
G02X906633Y59525I1200J2309D01*
G37*
G36*
G01X930481Y53911D02*
G03X930414Y53312I228J-329D01*
G02X927017Y53689I-1915J-1762D01*
G03X927084Y54288I-228J329D01*
G02Y57812I1915J1762D01*
G03X927017Y58411I-295J270D01*
G02X927299Y62859I1482J2139D01*
G03X927365Y63525I-185J355D01*
G02X930199Y63241I1634J2025D01*
G03X930133Y62575I185J-355D01*
G02X930414Y58788I-1634J-2025D01*
G03X930481Y58189I295J-270D01*
G02Y53911I-1482J-2139D01*
G37*
G36*
G01X303313Y37808D02*
G03X302727Y37769I-275J-290D01*
G02X302487Y41292I-2027J1632D01*
G03X303073Y41331I275J290D01*
G02X303311Y41589I2027J-1631D01*
G03X303231Y42229I-275J291D01*
G02X305709Y46804I1269J2271D01*
G03X306282Y47057I186J354D01*
G02X309980Y44081I2518J-657D01*
G03X309993Y43361I181J-357D01*
G02X307879Y38607I-1093J-2361D01*
G03X307373Y38433I-156J-368D01*
G02X303313Y37808I-2273J1267D01*
G37*
G36*
G01X943474Y31916D02*
G03X942808Y31850I-311J-251D01*
G02X942524Y34684I-2309J1200D01*
G03X943190Y34750I311J251D01*
G02X943474Y31916I2309J-1200D01*
G37*
G36*
G01X374549Y13827D02*
G03X373949I-300J-264D01*
G02X369458Y16110I-1950J1723D01*
G03X369192Y16576I-391J86D01*
G02X368276Y21000I807J2474D01*
G03Y21600I-264J300D01*
G02X371722I1723J1950D01*
G03Y21000I264J-300D01*
G02X372540Y18490I-1723J-1950D01*
G03X372806Y18024I391J-86D01*
G02X373949Y17273I-807J-2474D01*
G03X374549I300J264D01*
G02X378449I1950J-1723D01*
G03X379049I300J264D01*
G02X380136Y18005I1950J-1723D01*
G03X380336Y18604I-133J377D01*
G02X383362Y17595I2163J1446D01*
G03X383162Y16996I133J-377D01*
G02X379049Y13827I-2163J-1446D01*
G03X378449I-300J-264D01*
G02X374549I-1950J1723D01*
G37*
G36*
G01X226542Y54934D02*
G02X224456I-1043J-2384D01*
G03Y55666I-161J366D01*
G02Y60434I1043J2384D01*
G03Y61166I-161J366D01*
G02X224312Y65865I1043J2384D01*
G03X224332Y66566I-183J356D01*
G02X226666I1167J1984D01*
G03X226686Y65865I203J-345D01*
G02X226542Y61166I-1187J-2315D01*
G03Y60434I161J-366D01*
G02Y55666I-1043J-2384D01*
G03Y54934I161J-366D01*
G37*
G36*
G01X944542Y74934D02*
G02X942456I-1043J-2384D01*
G03Y75666I-161J366D01*
G02X941983Y80165I1043J2384D01*
G03X942009Y80795I-233J325D01*
G02X944989I1490J1755D01*
G03X945015Y80165I259J-305D01*
G02X944542Y75666I-1516J-2115D01*
G03Y74934I161J-366D01*
G37*
G36*
G01X168676Y105290D02*
G02X167422Y103410I1323J-2241D01*
G03X166822Y103810I-396J56D01*
G02X168076Y105690I-1323J2241D01*
G03X168676Y105290I396J-56D01*
G37*
G36*
G01X207516Y106659D02*
G02X205611Y107849I-2017J-1109D01*
G03X205982Y108441I20J400D01*
G02X207887Y107251I2017J1109D01*
G03X207516Y106659I-20J-400D01*
G37*
G36*
G01X37894Y117744D02*
G02X34970Y113672I-894J-2444D01*
G03X34357Y113685I-312J-250D01*
G02X31420Y117810I-1957J1715D01*
G03X31406Y118556I-151J370D01*
G02X34330Y122628I894J2444D01*
G03X34943Y122615I312J250D01*
G02X37880Y118490I1957J-1715D01*
G03X37894Y117744I151J-370D01*
G37*
G36*
G01X928893Y113742D02*
G02X928513Y116784I-1894J1308D01*
G03X929105Y116858I263J302D01*
G02X931745Y117728I1894J-1308D01*
G03X932263Y118201I130J378D01*
G02X935270Y120919I2236J549D01*
G03X935789Y121407I135J377D01*
G02X937228Y119881I2210J643D01*
G03X936709Y119393I-135J-377D01*
G02X933753Y116572I-2210J-643D01*
G03X933235Y116099I-130J-378D01*
G02X929485Y113816I-2236J-549D01*
G03X928893Y113742I-263J-302D01*
G37*
G36*
G01X25884Y196957D02*
G02Y199043I-2384J1043D01*
G03X26616I366J161D01*
G02Y196957I2384J-1043D01*
G03X25884I-366J-161D01*
G37*
G36*
G01X810813Y294738D02*
G02X807933I-1440J-2167D01*
G03Y295404I-222J333D01*
G02X808162Y299874I1440J2167D01*
G03X808112Y300604I-186J354D01*
G02X807462Y305150I887J2446D01*
G03X807512Y305752I-236J323D01*
G02X810910Y305471I1861J1819D01*
G03X810860Y304869I236J-323D01*
G02X810210Y300747I-1861J-1819D01*
G03X810260Y300017I186J-354D01*
G02X810813Y295404I-887J-2446D01*
G03Y294738I222J-333D01*
G37*
G36*
G01X750629Y1113044D02*
G02X746802Y1113523I-2130J-1494D01*
G03X746869Y1114056I-260J303D01*
G02X747597Y1117742I2130J1494D01*
G03X747731Y1118275I-215J337D01*
G02X752475Y1120350I2268J1275D01*
G03X753208Y1120283I381J123D01*
G02X753023Y1118250I2291J-1233D01*
G03X752290Y1118317I-381J-123D01*
G02X751401Y1117358I-2291J1233D01*
G03X751267Y1116825I215J-337D01*
G02X750696Y1113577I-2268J-1275D01*
G03X750629Y1113044I260J-303D01*
G37*
G36*
G01X960523Y1474450D02*
G02X957077I-1723J-1950D01*
G03Y1475050I-264J300D01*
G02Y1478950I1723J1950D01*
G03Y1479550I-264J300D01*
G02X957456Y1483728I1723J1950D01*
G03X957416Y1484434I-206J342D01*
G02X959844Y1484572I1083J2366D01*
G03X959884Y1483866I206J-342D01*
G02X960523Y1479550I-1084J-2366D01*
G03Y1478950I264J-300D01*
G02Y1475050I-1723J-1950D01*
G03Y1474450I264J-300D01*
G37*
G36*
G01X975223Y1475950D02*
G02X971777I-1723J-1950D01*
G03Y1476550I-264J300D01*
G02Y1480450I1723J1950D01*
G03Y1481050I-264J300D01*
G02X972156Y1485228I1723J1950D01*
G03X972116Y1485934I-206J342D01*
G02X974544Y1486072I1083J2366D01*
G03X974584Y1485366I206J-342D01*
G02X975223Y1481050I-1084J-2366D01*
G03Y1480450I264J-300D01*
G02Y1476550I-1723J-1950D01*
G03Y1475950I264J-300D01*
G37*
G36*
G01X967723Y1476950D02*
G02X964277I-1723J-1950D01*
G03Y1477550I-264J300D01*
G02Y1481450I1723J1950D01*
G03Y1482050I-264J300D01*
G02X964656Y1486228I1723J1950D01*
G03X964616Y1486934I-206J342D01*
G02X967044Y1487072I1083J2366D01*
G03X967084Y1486366I206J-342D01*
G02X967723Y1482050I-1084J-2366D01*
G03Y1481450I264J-300D01*
G02Y1477550I-1723J-1950D01*
G03Y1476950I264J-300D01*
G37*
G36*
G01X564542Y1488934D02*
G02X562456I-1043J-2384D01*
G03Y1489666I-161J366D01*
G02Y1494434I1043J2384D01*
G03Y1495166I-161J366D01*
G02X564542I1043J2384D01*
G03Y1494434I161J-366D01*
G02Y1489666I-1043J-2384D01*
G03Y1488934I161J-366D01*
G37*
G36*
G01X754634Y1764060D02*
G02X751271Y1768029I-1734J1940D01*
G03X751359Y1768555I-250J312D01*
G02X754997Y1772114I2199J1391D01*
G03X755525Y1772190I222J333D01*
G02X755657Y1772335I1989J-1678D01*
G03X755454Y1773006I-286J280D01*
G02X754265Y1773610I545J2544D01*
G03X753733I-266J-299D01*
G02X750370Y1777579I-1734J1940D01*
G03X750458Y1778105I-250J312D01*
G02X751156Y1781622I2199J1391D01*
G03X750926Y1782348I-231J326D01*
G01X637087D01*
X631636Y1787800D01*
Y1805997D01*
G02X636038I2201J1387D01*
G01Y1789624D01*
X638911Y1786752D01*
X758433D01*
X764621Y1792939D01*
X764634Y1792993D01*
G02X767788Y1789839I2525J-629D01*
G01X767734Y1789826D01*
X760257Y1782348D01*
X758956D01*
G03X758644Y1781698I0J-400D01*
G02X758027Y1777880I-2027J-1631D01*
G03X757944Y1777278I216J-337D01*
G02X757860Y1773732I-1945J-1728D01*
G03X758063Y1773061I286J-280D01*
G02X758928Y1768330I-545J-2544D01*
G03X758845Y1767728I216J-337D01*
G02X755166Y1764060I-1946J-1728D01*
G03X754634I-266J-299D01*
G37*
G36*
G01X881185Y1783941D02*
G02X878173Y1783967I-1521J-1728D01*
G03X878179Y1784572I-259J305D01*
G02X878026Y1784720I1522J1727D01*
G03X877690Y1784522I-146J-137D01*
G02X877582Y1784109I-381J-121D01*
G03X876795Y1781801I1782J-1896D01*
G02X876117Y1781455I-395J-63D01*
G01X809432Y1848141D01*
G02X809714Y1848824I283J283D01*
G01X813451D01*
X876763Y1785512D01*
G03X877439Y1785870I283J283D01*
G02X881191Y1784546I2261J430D01*
G03X881185Y1783941I259J-305D01*
G37*
G36*
G01X771383Y1929007D02*
G02Y1931093I-2384J1043D01*
G03X772115I366J161D01*
G02Y1929007I2384J-1043D01*
G03X771383I-366J-161D01*
G37*
G36*
G01X139772Y17617D02*
G02X121752Y23225I-9852J99D01*
G03X121421Y23848I-332J223D01*
G01X94516D01*
X94491Y23872D01*
X88528D01*
X83668Y28732D01*
G03X82987Y28481I-283J-283D01*
G02X77773Y33695I-4837J377D01*
G03X78024Y34376I-32J398D01*
G01X70298Y42103D01*
Y76548D01*
X71257Y77507D01*
G03X71116Y77848I-142J141D01*
G01X71001D01*
X69798Y79052D01*
Y86548D01*
X71001Y87752D01*
X88497D01*
X109200Y67048D01*
Y54299D01*
X110598Y52902D01*
X127597D01*
G03X127797Y53648I0J400D01*
G02X130403I1303J2252D01*
G03X130603Y52902I200J-346D01*
G01X145298D01*
X160948Y37252D01*
X186898D01*
G03X187244Y37851I0J400D01*
G02X191171Y41144I2255J1299D01*
G03X191771Y41244I257J306D01*
G02X192361Y41922I2228J-1343D01*
G03X192428Y42475I-251J311D01*
G02X196865Y42968I2071J1575D01*
G03X197332Y42415I364J-166D01*
G02X199723Y37951I667J-2515D01*
G03X199988Y37252I265J-299D01*
G01X252001D01*
X277298Y62548D01*
Y78548D01*
X283001Y84252D01*
X297997D01*
X299200Y83048D01*
Y72916D01*
G03X299883Y72633I400J0D01*
G01X300298Y73048D01*
Y82048D01*
X302501Y84252D01*
X316997D01*
X318200Y83048D01*
Y65552D01*
X311497Y58848D01*
X305997D01*
X289472Y42324D01*
G03X289721Y41643I283J-283D01*
G02X289402Y36450I-222J-2593D01*
G03X289016Y35901I-15J-400D01*
G02X286700Y37528I-2413J-973D01*
G03X287086Y38077I15J400D01*
G02X286906Y38828I2412J975D01*
G03X286225Y39077I-398J-34D01*
G01X264497Y17348D01*
X141001D01*
X140454Y17896D01*
G03X139772Y17617I-282J-283D01*
G37*
G36*
G01X35518Y1432362D02*
Y1432354D01*
G02Y1432304I-2312J-25D01*
G01Y1432264D01*
X35515Y1432229D01*
G02X31750Y1430555I-2309J123D01*
G01X31744Y1430547D01*
X29034Y1432749D01*
X29036Y1432752D01*
X28961Y1432824D01*
G02X31955Y1436347I1538J1726D01*
G01X31961Y1436355D01*
X34175Y1434558D01*
X34173D01*
X34179Y1434552D01*
X34181D01*
X34670Y1434155D01*
Y1434143D01*
X34689Y1434126D01*
G02X35518Y1432362I-1483J-1774D01*
G37*
G36*
G01X34099Y1495238D02*
X30499D01*
G02Y1499862I0J2312D01*
G01X34099D01*
G02X36410Y1497560I0J-2311D01*
G01Y1497462D01*
X36404Y1497374D01*
G02X34099Y1495238I-2305J176D01*
G37*
G36*
G01X33386Y1479650D02*
X33352Y1479668D01*
X31666Y1479846D01*
X31628Y1479836D01*
G02X32078Y1484083I-629J2214D01*
G01X32112Y1484065D01*
X33798Y1483887D01*
X33835Y1483897D01*
G02X33386Y1479650I630J-2214D01*
G37*
G36*
G01X34021Y1460372D02*
X30485Y1460209D01*
G02X30272Y1464827I-106J2309D01*
G01X33809Y1464990D01*
G02X36208Y1462390I106J-2309D01*
G01X36203Y1462355D01*
G02X34021Y1460372I-2288J326D01*
G37*
G36*
G01X29482Y1450460D02*
X29519Y1450447D01*
X31083Y1450517D01*
X31119Y1450533D01*
G02X31309Y1446284I975J-2085D01*
G01X31272Y1446297D01*
X29708Y1446228D01*
X29672Y1446211D01*
G02X29482Y1450460I-975J2085D01*
G37*
G36*
G01X29052Y1413851D02*
Y1413861D01*
X32506Y1413778D01*
X32514Y1413770D01*
X32589Y1413766D01*
G02X32398Y1409167I-138J-2298D01*
G01Y1409157D01*
X28942Y1409240D01*
Y1409242D01*
X28763Y1409260D01*
G02X29052Y1413851I237J2290D01*
G37*
G36*
G01X27809Y1372022D02*
Y1372020D01*
X27859Y1368514D01*
Y1368512D01*
G02X23256Y1368448I-2301J-66D01*
G01Y1368449D01*
X23206Y1371978D01*
Y1371979D01*
G02X27809Y1372022I2301J65D01*
G37*
G36*
G01X23543Y1166884D02*
G02X21457I-1043J-2384D01*
G03Y1167616I-161J366D01*
G02X23543I1043J2384D01*
G03Y1166884I161J-366D01*
G37*
G36*
G01X7543Y1100384D02*
G02X5457I-1043J-2384D01*
G03Y1101116I-161J366D01*
G02X7543I1043J2384D01*
G03Y1100384I161J-366D01*
G37*
G36*
G01X269939Y704383D02*
G03Y703717I222J-333D01*
G02X267059I-1440J-2167D01*
G03Y704383I-222J333D01*
G02Y708717I1440J2167D01*
G03Y709383I-222J333D01*
G02Y713717I1440J2167D01*
G03Y714383I-222J333D01*
G02X269939I1440J2167D01*
G03Y713717I222J-333D01*
G02Y709383I-1440J-2167D01*
G03Y708717I222J-333D01*
G02Y704383I-1440J-2167D01*
G37*
G36*
G01X183600Y558400D02*
X183688Y558396D01*
X282710Y657418D01*
Y698850D01*
G03X282136Y699209I-400J-1D01*
G02X279059Y703284I-1137J2341D01*
G03Y703816I-299J266D01*
G02X282136Y707891I1940J1734D01*
G03X282710Y708250I174J360D01*
G01Y711248D01*
G03X282060Y711560I-400J0D01*
G02X278757Y715581I-1628J2030D01*
G03X278833Y716108I-257J306D01*
G02X282136Y719891I2166J1442D01*
G03X282710Y720250I174J360D01*
G01Y723732D01*
X280128Y726314D01*
X280040Y726310D01*
G02X282239Y728509I-101J2300D01*
G01X282235Y728421D01*
X285690Y724966D01*
Y656184D01*
X185795Y556289D01*
X185799Y556201D01*
G02X183600Y558400I-2300J-101D01*
G37*
G36*
G01X177874Y440452D02*
G03X177920Y440985I-273J292D01*
G02X178276Y444500I2079J1565D01*
G03Y445100I-264J300D01*
G02X181733Y448990I1723J1950D01*
G03X182265I266J299D01*
G02X185722Y445100I1734J-1940D01*
G03Y444500I264J-300D01*
G02X185939Y440816I-1723J-1950D01*
G03Y440284I299J-266D01*
G02X182114Y436757I-1940J-1734D01*
G03X181534I-290J-276D01*
G02X177874Y440452I-1885J1793D01*
G37*
G36*
G01X189222Y533563D02*
G02X185776I-1723J-1950D01*
G03Y534163I-264J300D01*
G02X186918Y538649I1723J1950D01*
G03X187118Y539315I-89J390D01*
G02X187276Y543063I1881J1798D01*
G03Y543663I-264J300D01*
G02X187059Y547347I1723J1950D01*
G03Y547879I-299J266D01*
G02X190949Y551336I1940J1734D01*
G03X191549I300J264D01*
G02X195605Y548085I1950J-1723D01*
G03X195671Y547543I323J-236D01*
G02X195511Y543432I-1672J-1994D01*
G03X195444Y542841I232J-326D01*
G02X191549Y539390I-1945J-1728D01*
G03X190949I-300J-264D01*
G02X189580Y538577I-1949J1723D01*
G03X189380Y537911I89J-390D01*
G02X189222Y534163I-1881J-1798D01*
G03Y533563I264J-300D01*
G37*
G36*
G01X23987Y478442D02*
X23986Y478548D01*
X23981Y478549D01*
X24198Y481948D01*
X24201Y481947D01*
X24217Y482057D01*
G02X28825Y481901I2298J-259D01*
G01X28826Y481891D01*
Y481882D01*
G02X28827Y481808I-2311J-68D01*
G01X28828D01*
Y481806D01*
X28826D01*
Y481800D01*
X28828D01*
Y481798D01*
X28827D01*
G02X28826Y481721I-2312J-8D01*
G01Y481654D01*
X28833Y481653D01*
X28626Y478412D01*
X28622D01*
Y478406D01*
X28626D01*
X28616Y478257D01*
X28614Y478254D01*
X28607Y478255D01*
X28606Y478244D01*
G02X23987Y478442I-2307J160D01*
G37*
G36*
G01X28710Y505751D02*
Y501878D01*
X28704Y501790D01*
G02X24088Y501966I-2305J176D01*
G01Y505741D01*
G02X28710Y505751I2311J0D01*
G37*
G36*
G01X24601Y454606D02*
X24582Y454784D01*
X24579D01*
X24478Y458434D01*
X24481D01*
X24491Y458624D01*
G02X25189Y460155I2308J-128D01*
G03X25142Y460768I-279J287D01*
G02X24175Y462656I1344J1880D01*
G01X24188Y466258D01*
G02X28810Y466260I2311J-8D01*
G01Y466250D01*
X28811D01*
G02Y466242I-2312J-4D01*
G01X28798Y462658D01*
Y462641D01*
G02X28797Y462624I-2305J127D01*
G01Y462555D01*
X28791Y462472D01*
G02X28096Y460990I-2305J177D01*
G03X28143Y460378I279J-286D01*
G02X29097Y458741I-1345J-1880D01*
G01X29116Y458562D01*
X29120D01*
X29220Y454914D01*
X29210Y454905D01*
Y454762D01*
X29204Y454674D01*
G02X24601Y454606I-2305J176D01*
G37*
G36*
G01X24182Y439423D02*
X24289Y442822D01*
G02X28910Y442759I2310J-73D01*
G01Y442749D01*
X28911D01*
G02Y442739I-2312J-5D01*
G01X28910D01*
Y442708D01*
X28802Y439235D01*
X28797Y439174D01*
G02X24182Y439423I-2305J176D01*
G37*
G36*
G01X149431Y542303D02*
G03X149394Y542981I-229J327D01*
G02X151819Y543113I1106J2019D01*
G03X151856Y542435I229J-327D01*
G02X151393Y538206I-1106J-2019D01*
G03X151253Y537973I56J-192D01*
G02X148357Y539710I-2253J-473D01*
G03X148497Y539943I-56J192D01*
G02X149431Y542303I2253J473D01*
G37*
G36*
G01X150515Y522572D02*
G02X150050Y519589I1485J-1759D01*
G03X149429Y519659I-338J-213D01*
G02X146172Y523682I-1839J1841D01*
G03X146133Y524374I-218J335D01*
G02X148718Y524518I1167J2326D01*
G03X148757Y523826I218J-335D01*
G02X149902Y522694I-1167J-2326D01*
G03X150515Y522572I355J184D01*
G37*
G36*
G01X98900Y511088D02*
X95500D01*
G02Y515712I0J2312D01*
G01X98900D01*
G02X101212Y513410I0J-2312D01*
G01Y513312D01*
X101205Y513224D01*
G02X98900Y511088I-2305J176D01*
G37*
G36*
G01X29998Y671111D02*
Y667359D01*
X29992Y667271D01*
G02X25376Y667447I-2305J176D01*
G01Y671101D01*
G02X29998Y671111I2311J0D01*
G37*
G36*
G01X29044Y651824D02*
X29042D01*
X29019Y651651D01*
G02X24435Y651910I-2282J306D01*
G01X24432Y652087D01*
X24429Y652088D01*
X24692Y656684D01*
X24693D01*
X24720Y656874D01*
G02X29301Y656597I2279J-323D01*
G01X29304Y656420D01*
X29307Y656419D01*
X29045Y651839D01*
X29044Y651824D01*
G37*
G36*
G01X28870Y639556D02*
Y635996D01*
G02X24266I-2302J-46D01*
G01Y639558D01*
G02X28870I2302J46D01*
G01Y639556D01*
G37*
G36*
G01X29800Y623809D02*
Y620251D01*
X29801Y620249D01*
G02X25197I-2302J-46D01*
G01X25198Y620251D01*
Y623809D01*
X25197Y623811D01*
G02X29801I2302J46D01*
G01X29800Y623809D01*
G37*
G36*
G01X43499Y660752D02*
X50173D01*
X159735Y770314D01*
G02X164263Y765786I2264J-2264D01*
G01X52825Y654348D01*
X43499D01*
G02Y660752I0J3202D01*
G37*
G36*
G01X77669Y848932D02*
G03X77586Y848673I98J-174D01*
G02X73300Y847023I-2086J-974D01*
G03X72835Y847297I-382J-117D01*
G02X70793Y851235I-473J2253D01*
G03X70803Y851810I-273J292D01*
G01X70022Y852592D01*
Y975339D01*
X78640Y983958D01*
G03X78342Y984640I-283J283D01*
G02X80971Y993435I-192J4848D01*
G03X81510Y993504I232J326D01*
G02X81817Y993648I307J-256D01*
G01X86560D01*
Y994437D01*
X89713Y997590D01*
X90845D01*
G02X92673Y993799I1755J-1490D01*
G03X92288Y993355I12J-400D01*
G02X91490Y991345I-2288J-255D01*
G01Y990083D01*
X74776Y973369D01*
Y858371D01*
X78029Y855117D01*
Y852693D01*
G02X77669Y848932I-1489J-1755D01*
G37*
G36*
G01X261233Y1163490D02*
G03X261765I266J299D01*
G02X265449Y1163273I1734J-1940D01*
G03X266049I300J264D01*
G02X269733Y1163490I1950J-1723D01*
G03X270265I266J299D01*
G02Y1159610I1734J-1940D01*
G03X269733I-266J-299D01*
G02X266049Y1159827I-1734J1940D01*
G03X265449I-300J-264D01*
G02X261765Y1159610I-1950J1723D01*
G03X261233I-266J-299D01*
G02Y1163490I-1734J1940D01*
G37*
G36*
G01X262294Y1151085D02*
G03X261761Y1151077I-262J-302D01*
G02X261704Y1154957I-1762J1915D01*
G03X262237Y1154965I262J302D01*
G02X265949Y1154773I1762J-1915D01*
G03X266549I300J264D01*
G02X270233Y1154990I1950J-1723D01*
G03X270765I266J299D01*
G02Y1151110I1734J-1940D01*
G03X270233I-266J-299D01*
G02X266549Y1151327I-1734J1940D01*
G03X265949I-300J-264D01*
G02X262294Y1151085I-1950J1723D01*
G37*
G36*
G01X230736Y1075703D02*
G03X231298Y1076069I162J365D01*
G01Y1085788D01*
X225719Y1091367D01*
X225694Y1091381D01*
G02X228819Y1094506I1106J2019D01*
G01X228833Y1094481D01*
X235701Y1087612D01*
Y1066773D01*
X235710Y1066746D01*
G02X231290I-2210J-646D01*
G01X231298Y1066773D01*
Y1071131D01*
G03X230736Y1071497I-400J1D01*
G02Y1075703I-936J2103D01*
G37*
G36*
G01X126310Y1054060D02*
Y1050562D01*
X126304Y1050474D01*
G02X121688Y1050650I-2305J176D01*
G01Y1054051D01*
G02X126310Y1054060I2311J-1D01*
G37*
G36*
G01X216949Y950336D02*
G03X217549I300J264D01*
G02X221062Y946533I1950J-1723D01*
G03Y945893I240J-320D01*
G02X221358Y941993I-1563J-2080D01*
G03Y941433I286J-280D01*
G02X217549Y937890I-1859J-1820D01*
G03X216949I-300J-264D01*
G02X213276Y941563I-1950J1723D01*
G03Y942163I-264J300D01*
G02Y946063I1723J1950D01*
G03Y946663I-264J300D01*
G02X216949Y950336I1723J1950D01*
G37*
G36*
G01X88710Y937060D02*
Y936962D01*
X88704Y936874D01*
G02X84104Y936778I-2305J177D01*
G01X83704Y940156D01*
G02X88294Y940701I2295J272D01*
G01X88326Y940438D01*
X88694Y937322D01*
G02X88710Y937060I-2295J-272D01*
G37*
G36*
G01X150865Y933575D02*
G03X150799Y934241I-251J311D01*
G02X153633Y934525I1200J2309D01*
G03X153699Y933859I251J-311D01*
G02X150865Y933575I-1200J-2309D01*
G37*
G36*
G01X111410Y928260D02*
Y928162D01*
X111404Y928074D01*
G02X106794Y928078I-2305J177D01*
G01X106540Y931485D01*
G02X111149Y931842I2305J172D01*
G01X111152Y931805D01*
X111404Y928423D01*
G02X111410Y928260I-2305J-166D01*
G37*
G36*
G01X95100Y903850D02*
X95188Y903846D01*
X111382Y920040D01*
X151744D01*
G02Y917060I1755J-1490D01*
G01X112616D01*
X97295Y901739D01*
X97299Y901651D01*
G02X95100Y903850I-2300J-101D01*
G37*
G36*
G01X213802Y885523D02*
G03X213869Y886056I-260J303D01*
G02X217949Y889273I2130J1494D01*
G03X218549I300J264D01*
G02Y885827I1950J-1723D01*
G03X217949I-300J-264D01*
G02X217696Y885577I-1951J1722D01*
G03X217629Y885044I260J-303D01*
G02X213802Y885523I-2130J-1494D01*
G37*
G36*
G01X145497Y878348D02*
X92001D01*
X89798Y880552D01*
Y889048D01*
X90550Y889800D01*
X90298Y890052D01*
Y894048D01*
X92001Y895752D01*
X136001D01*
X154001Y913752D01*
X161497D01*
X163200Y912048D01*
Y904552D01*
X160082Y901434D01*
G03X160365Y900752I283J-282D01*
G01X168497D01*
X169700Y899548D01*
Y892552D01*
X165997Y888848D01*
X156886D01*
G02X155672Y888454I-1386J2202D01*
G01X155597Y888449D01*
X145497Y878348D01*
G37*
G36*
G01X162865Y867751D02*
X168997D01*
X170700Y866048D01*
Y860052D01*
X167497Y856848D01*
X159497D01*
X150497Y847848D01*
X89001D01*
X87298Y849552D01*
Y857048D01*
X89550Y859300D01*
X88798Y860052D01*
Y863548D01*
X90501Y865252D01*
X136001D01*
X151001Y880252D01*
X159497D01*
X163200Y876548D01*
Y869052D01*
X162582Y868434D01*
G03X162865Y867751I283J-283D01*
G37*
G36*
G01X101185Y965726D02*
G02X99456Y967256I-2184J-727D01*
G03X99915Y967774I79J392D01*
G02X101644Y966244I2184J727D01*
G03X101185Y965726I-79J-392D01*
G37*
G36*
G01X133110Y1731900D02*
G03X132777Y1731307I17J-400D01*
G02X128525Y1731746I-2278J-1257D01*
G03X128192Y1732405I-303J260D01*
G02X130309Y1736200I-192J2595D01*
G03X130975Y1736134I355J185D01*
G02X133110Y1731900I2025J-1634D01*
G37*
G36*
G01X141924Y1731445D02*
G03X142590Y1731318I373J145D01*
G02X142075Y1728605I1909J-1768D01*
G03X141409Y1728732I-373J-145D01*
G02X141924Y1731445I-1909J1768D01*
G37*
G36*
G01X166049Y1724890D02*
G03X165449I-300J-264D01*
G02X162813Y1729123I-1950J1723D01*
G03X163079Y1729656I-106J386D01*
G02X167542Y1732225I2420J958D01*
G03X168208Y1732283I314J248D01*
G02X172755Y1729753I2291J-1233D01*
G03X173021Y1729162I347J-199D01*
G02X170549Y1724890I-522J-2549D01*
G03X169949I-300J-264D01*
G02X166049I-1950J1723D01*
G37*
G36*
G01X170314Y1712637D02*
G03X169648Y1712646I-336J-217D01*
G02X165332Y1712673I-2149J1467D01*
G03X164666I-333J-222D01*
G02Y1715553I-2167J1440D01*
G03X165332I333J222D01*
G02X169684Y1715526I2167J-1440D01*
G03X170350Y1715517I336J217D01*
G02X170314Y1712637I2149J-1467D01*
G37*
G36*
G01X170510Y1688306D02*
Y1692884D01*
X151946Y1711448D01*
X151825Y1711401D01*
G02X153073Y1714550I-826J2149D01*
G01X153087Y1714519D01*
X171790Y1695817D01*
G03X172395Y1695863I283J283D01*
G02X173942Y1692219I1855J-1363D01*
G03X173488Y1691822I-54J-397D01*
G01Y1664005D01*
G02X170510I-1489J-1755D01*
G01Y1679647D01*
G03X170034Y1680039I-400J-1D01*
G02X167757Y1683680I-434J2261D01*
G03X167717Y1683959I-160J119D01*
G02X169960Y1687935I1382J1841D01*
G03X170510Y1688306I150J371D01*
G37*
G36*
G01X178163Y1628036D02*
G03X178088Y1628574I-328J228D01*
G02X178057Y1632581I1645J2016D01*
G03X178133Y1633108I-257J306D01*
G02X181975Y1632559I2166J1442D01*
G03X181899Y1632032I257J-306D01*
G02X181869Y1629104I-2166J-1442D01*
G03X181944Y1628566I328J-228D01*
G02X178163Y1628036I-1645J-2016D01*
G37*
G36*
G01X98309Y1536605D02*
G03X98521Y1536776I14J199D01*
G02X98803Y1537595I2279J-327D01*
G03X98731Y1537866I-174J99D01*
G02X101896Y1538705I1168J1984D01*
G03X101968Y1538434I174J-99D01*
G02X100635Y1534154I-1168J-1984D01*
G03X100423Y1533983I-14J-199D01*
G02X98309Y1536605I-2279J326D01*
G37*
G36*
G01X126314Y1468144D02*
X126295Y1468110D01*
X126018Y1465696D01*
X126028Y1465659D01*
G02X121784Y1466147I-2220J-609D01*
G01X121803Y1466181D01*
X122080Y1468594D01*
X122070Y1468632D01*
G02X126314Y1468144I2220J609D01*
G37*
G36*
G01X145310Y1456427D02*
Y1456285D01*
X145304Y1456197D01*
G02X140700Y1456130I-2305J175D01*
G01X140682Y1456308D01*
X140679D01*
X140579Y1459938D01*
X140582D01*
X140592Y1460127D01*
G02X145199Y1460243I2308J-126D01*
G01X145217Y1460064D01*
X145221D01*
X145320Y1456436D01*
X145310Y1456427D01*
G37*
G36*
G01X107311Y1444907D02*
X107246Y1440535D01*
X107240Y1440458D01*
G02X102624Y1440668I-2305J176D01*
G01X102688Y1444975D01*
G02X107310Y1444951I2311J-34D01*
G01Y1444941D01*
X107311Y1444940D01*
G02Y1444908I-2312J-16D01*
G01Y1444907D01*
G37*
G36*
G01X119702Y1429986D02*
Y1426113D01*
X119695Y1426025D01*
G02X115078Y1426201I-2305J176D01*
G01Y1429976D01*
G02X119702Y1429986I2312J0D01*
G37*
G36*
G01X99541Y1373345D02*
Y1373249D01*
X99534Y1373161D01*
G02X94921Y1373213I-2305J177D01*
G01X94692Y1377476D01*
G02X99304Y1377785I2308J124D01*
G01X99308Y1377742D01*
X99537Y1373462D01*
G02X99541Y1373345I-2308J-137D01*
G37*
G36*
G01X179476Y1367225D02*
G03X179402Y1367877I-265J300D01*
G02X182024Y1368175I1098J2023D01*
G03X182098Y1367523I265J-300D01*
G02X179476Y1367225I-1098J-2023D01*
G37*
G36*
G01X121052Y1361182D02*
G03X120724Y1361715I-376J136D01*
G02X122205Y1365961I275J2285D01*
G03X122812Y1366257I210J341D01*
G02X123895Y1364039I2288J-256D01*
G03X123288Y1363743I-210J-341D01*
G02X123223Y1363404I-2287J263D01*
G03X123595Y1362900I386J-104D01*
G02X121052Y1361182I-95J-2600D01*
G37*
G36*
G01X114785Y1358204D02*
X114720Y1357817D01*
G02X110160Y1358576I-2280J380D01*
G01X110719Y1361930D01*
G02X115310Y1361560I2280J-379D01*
G01Y1361550D01*
X115311D01*
G02Y1361545I-2312J-3D01*
G01X115310Y1361544D01*
Y1361460D01*
X115304Y1361374D01*
G02X115279Y1361170I-2305J179D01*
G01X114785Y1358204D01*
G37*
G36*
G01X104662Y1348164D02*
Y1344412D01*
X104655Y1344324D01*
G02X100038Y1344500I-2305J176D01*
G01Y1348154D01*
G02X104662Y1348164I2312J0D01*
G37*
G36*
G01X89192Y1346587D02*
Y1342906D01*
G02X84588I-2302J-46D01*
G01Y1346589D01*
G02X89192I2302J46D01*
G01Y1346587D01*
G37*
G36*
G01X111540Y1337100D02*
Y1333227D01*
X111533Y1333139D01*
G02X106916Y1333315I-2305J176D01*
G01Y1337091D01*
G02X111540Y1337100I2312J-1D01*
G37*
G36*
G01X118832Y1326517D02*
G03X118238Y1326505I-292J-274D01*
G02X118174Y1329592I-1739J1508D01*
G03X118768Y1329604I292J274D01*
G02X118832Y1326517I1739J-1508D01*
G37*
G36*
G01X166736Y1310348D02*
X166673D01*
X146017Y1331004D01*
G03X145433Y1330985I-283J-282D01*
G02X142079Y1330866I-1733J1515D01*
G03X141531Y1330881I-282J-284D01*
G02X141621Y1334234I-1531J1719D01*
G03X142169Y1334219I282J284D01*
G02X144583Y1334626I1531J-1719D01*
G03X145101Y1334832I153J369D01*
G02X150288Y1335789I2923J-1307D01*
G01X169325Y1316752D01*
X169388D01*
X177763Y1308377D01*
G02X177920Y1308208I-2266J-2262D01*
G03X178459Y1308147I303J262D01*
G02X181722Y1304100I1540J-2097D01*
G03Y1303500I264J-300D01*
G02X181480Y1299410I-1723J-1950D01*
G03Y1298753I227J-328D01*
G02X181915Y1294852I-1481J-2140D01*
G03Y1294311I294J-270D01*
G02X178049Y1290827I-1916J-1761D01*
G03X177449I-300J-264D01*
G02X173937Y1294631I-1950J1723D01*
G03X173980Y1295233I-240J320D01*
G02X174280Y1299165I1843J1837D01*
G03X174237Y1299837I-237J322D01*
G02X173420Y1303678I1262J2276D01*
G02X173235Y1303849I2079J2435D01*
G01X166736Y1310348D01*
G37*
G36*
G01X146029Y1231912D02*
G03X146606I288J277D01*
G02X150432Y1228386I1879J-1800D01*
G03X150434Y1227853I299J-265D01*
G02X150439Y1224379I-1935J-1740D01*
G03Y1223847I299J-266D01*
G02X146614Y1220320I-1940J-1734D01*
G03X146034I-290J-276D01*
G02X142209Y1223847I-1885J1793D01*
G03Y1224379I-299J266D01*
G02Y1227847I1940J1734D01*
G03Y1228379I-299J266D01*
G02X146029Y1231912I1940J1735D01*
G37*
G36*
G01X125166Y1223540D02*
X125301Y1223458D01*
X178832Y1276990D01*
X180745D01*
G02Y1274010I1755J-1490D01*
G01X180066D01*
X126139Y1220084D01*
X125727D01*
X125668Y1220019D01*
G02X125166Y1223540I-1698J1554D01*
G37*
G36*
G01X104786Y1193914D02*
G03X104180Y1194136I-384J-110D01*
G02X105113Y1196686I-1280J1914D01*
G03X105719Y1196464I384J110D01*
G02X104786Y1193914I1280J-1914D01*
G37*
G36*
G01X112930Y1132294D02*
G03X113490Y1132261I297J268D01*
G02X116947Y1128371I1710J-1961D01*
G03X116920Y1127805I268J-296D01*
G02X116939Y1124316I-1921J-1755D01*
G03Y1123784I299J-266D01*
G02Y1120316I-1940J-1734D01*
G03Y1119784I299J-266D01*
G02X113265Y1116110I-1940J-1734D01*
G03X112733I-266J-299D01*
G02X109059Y1119784I-1734J1940D01*
G03Y1120316I-299J266D01*
G02Y1123784I1940J1734D01*
G03Y1124316I-299J266D01*
G02X109276Y1128000I1940J1734D01*
G03Y1128600I-264J300D01*
G02X112930Y1132294I1723J1950D01*
G37*
G36*
G01X99276Y1097000D02*
G03Y1097600I-264J300D01*
G02X102295Y1101806I1723J1950D01*
G03X102828Y1101933I199J347D01*
G02X106307Y1102750I2172J-1433D01*
G03X106876Y1102941I200J346D01*
G02X108031Y1099961I2123J-891D01*
G03X107482Y1099718I-168J-363D01*
G02X106352Y1098277I-2482J782D01*
G03Y1097593I207J-342D01*
G02X103421Y1093302I-1346J-2227D01*
G03X102888Y1093260I-243J-317D01*
G02X99276Y1097000I-1889J1790D01*
G37*
G36*
G01X97889Y1551664D02*
G02X95618Y1552327I-1689J-1564D01*
G03X95810Y1552986I-101J387D01*
G02X95656Y1555930I1689J1564D01*
G03X95616Y1556209I-160J119D01*
G02X97520Y1560292I1383J1841D01*
G01X97606Y1560272D01*
X155538Y1599990D01*
X158445D01*
G02X159874Y1596221I1755J-1490D01*
G03X159650Y1596065I-28J-198D01*
G02X156902Y1594302I-2250J485D01*
G01X156816Y1594322D01*
X99793Y1554339D01*
X99782Y1554252D01*
G02X98081Y1552323I-2283J298D01*
G03X97889Y1551664I101J-387D01*
G37*
G36*
G01X83883Y1588007D02*
G02X79245Y1590350I-2384J1043D01*
G03X78912Y1590949I-347J199D01*
G02X77265Y1591610I88J2601D01*
G03X76733I-266J-299D01*
G02X73276Y1595500I-1734J1940D01*
G03Y1596100I-264J300D01*
G02X73059Y1599784I1723J1950D01*
G03Y1600316I-299J266D01*
G02X76733Y1603990I1940J1734D01*
G03X77265I266J299D01*
G02X80949Y1603773I1734J-1940D01*
G03X81549I300J264D01*
G02X85439Y1600316I1950J-1723D01*
G03Y1599784I299J-266D01*
G02Y1596316I-1940J-1734D01*
G03Y1595784I299J-266D01*
G02X83700Y1591456I-1940J-1734D01*
G03X83434Y1590790I32J-399D01*
G02X83883Y1590093I-1935J-1740D01*
G03X84615I366J161D01*
G02X89383I2384J-1043D01*
G03X90115I366J161D01*
G02Y1588007I2384J-1043D01*
G03X89383I-366J-161D01*
G02X84615I-2384J1043D01*
G03X83883I-366J-161D01*
G37*
G36*
G01X107087Y1739497D02*
X107081Y1739606D01*
X107077D01*
X107178Y1743608D01*
X107180Y1743610D01*
X107181D01*
X107187Y1743617D01*
X107189Y1743640D01*
G02X111809Y1743653I2310J-90D01*
G01X111810Y1743643D01*
Y1743634D01*
G02X111811Y1743560I-2311J-68D01*
G01X111812D01*
Y1743558D01*
X111810D01*
Y1743552D01*
X111812D01*
Y1743550D01*
X111811D01*
Y1743494D01*
X111821D01*
X111722Y1739558D01*
Y1739552D01*
X111720Y1739490D01*
X111717D01*
X111704Y1739373D01*
G02X107087Y1739497I-2305J177D01*
G37*
G36*
G01X82885Y1748948D02*
X83032Y1752344D01*
G02X87652Y1752255I2309J-98D01*
G01Y1752245D01*
X87653D01*
G02Y1752238I-2312J-4D01*
G01X87652Y1752237D01*
Y1752191D01*
X87502Y1748717D01*
X87499Y1748672D01*
G02X82885Y1748948I-2305J176D01*
G37*
G36*
G01X308859Y1567965D02*
G03X308268Y1567842I-242J-318D01*
G02X307753Y1571035I-2270J1272D01*
G03X308352Y1571104I269J296D01*
G02X308859Y1567965I1897J-1304D01*
G37*
G36*
G01X291732Y1580054D02*
G03X292264I266J299D01*
G02X295721Y1576164I1734J-1940D01*
G03Y1575564I264J-300D01*
G02Y1571664I-1723J-1950D01*
G03Y1571064I264J-300D01*
G02X292264Y1567174I-1723J-1950D01*
G03X291732I-266J-299D01*
G02X288275Y1571064I-1734J1940D01*
G03Y1571664I-264J300D01*
G02Y1575564I1723J1950D01*
G03Y1576164I-264J300D01*
G02X291732Y1580054I1723J1950D01*
G37*
G36*
G01X281609Y1557695D02*
G03X281889I140J143D01*
G02Y1554405I1610J-1645D01*
G03X281609I-140J-143D01*
G02Y1557695I-1610J1645D01*
G37*
G36*
G01X280712Y1528452D02*
G03X280779Y1527923I329J-227D01*
G02X276930Y1527430I-1704J-1966D01*
G03X276863Y1527959I-329J227D01*
G02X280712Y1528452I1704J1966D01*
G37*
G36*
G01X269119Y1520643D02*
G03Y1520057I273J-293D01*
G02X265579I-1770J-1907D01*
G03Y1520643I-273J293D01*
G02X265688Y1524553I1770J1907D01*
G03Y1525169I-255J308D01*
G02X269010I1661J2003D01*
G03Y1524553I255J-308D01*
G02X269119Y1520643I-1661J-2003D01*
G37*
G36*
G01X281222Y1513100D02*
G03Y1512500I264J-300D01*
G02X277776I-1723J-1950D01*
G03Y1513100I-264J300D01*
G02X281222I1723J1950D01*
G37*
G36*
G01X197328Y1621130D02*
G02X193985Y1621057I-1628J-2030D01*
G03X193972Y1621670I-263J301D01*
G02X196692Y1626062I1628J2030D01*
G03X197251Y1626510I168J363D01*
G02X198644Y1624863I2249J490D01*
G03X198110Y1624386I-148J-371D01*
G02X197315Y1621743I-2510J-686D01*
G03X197328Y1621130I263J-301D01*
G37*
G36*
G01X75192Y1811631D02*
G02X71048Y1808122I-4144J692D01*
G01X66748D01*
G02Y1816524I0J4201D01*
G01X67864D01*
G03X68264Y1816918I0J400D01*
G02X68381Y1817194I400J-7D01*
G01X70134Y1818948D01*
X75680D01*
G02X75949Y1818252I0J-400D01*
G03X77206Y1814267I1550J-1702D01*
G02X77438Y1813587I-51J-397D01*
G01X75931Y1812080D01*
G02X75617Y1811964I-283J283D01*
G03X75192Y1811631I-30J-399D01*
G37*
G36*
G01X292264Y350174D02*
G03X291732I-266J-299D01*
G02X288275Y354064I-1734J1940D01*
G03Y354664I-264J300D01*
G02Y358564I1723J1950D01*
G03Y359164I-264J300D01*
G02X291732Y363054I1723J1950D01*
G03X292264I266J299D01*
G02X295721Y359164I1734J-1940D01*
G03Y358564I264J-300D01*
G02Y354664I-1723J-1950D01*
G03Y354064I264J-300D01*
G02X292264Y350174I-1723J-1950D01*
G37*
G36*
G01X305229Y755469D02*
G03X305274Y756102I-221J334D01*
G02X308256Y755772I1725J1948D01*
G03X308160Y755144I193J-351D01*
G02X305229Y755469I-1660J-1594D01*
G37*
G36*
G01X880366Y1456460D02*
Y1456452D01*
G02Y1456402I-2312J-25D01*
G01Y1456362D01*
X880363Y1456327D01*
G02X879598Y1454729I-2309J123D01*
G02X876189Y1455084I-1544J1720D01*
G02X875757Y1456186I1865J1367D01*
G01X875739Y1456317D01*
X875736Y1456316D01*
X875534Y1459862D01*
X875539Y1459863D01*
X875541Y1459974D01*
G02X880161Y1460124I2312J17D01*
G01X880171Y1460125D01*
X880179Y1459998D01*
X880168D01*
Y1459994D01*
X880178D01*
X880373Y1456581D01*
X880370Y1456578D01*
X880369D01*
X880364Y1456574D01*
Y1456545D01*
G02X880366Y1456460I-2310J-97D01*
G37*
G36*
G01X800765Y1095626D02*
G03X800233I-266J-299D01*
G02Y1099506I-1734J1940D01*
G03X800765I266J299D01*
G02X804812Y1098758I1734J-1940D01*
G03X805478Y1098689I356J183D01*
G02X805559Y1098785I2029J-1630D01*
G03X805538Y1099340I-298J267D01*
G02X805661Y1103203I1803J1876D01*
G03X805615Y1103847I-259J305D01*
G02X805833Y1108376I1384J2203D01*
G03X805878Y1109064I-180J357D01*
G02X805901Y1113383I1463J2152D01*
G03Y1114049I-222J333D01*
G02X808781I1440J2167D01*
G03Y1113383I222J-333D01*
G02X808507Y1108890I-1440J-2167D01*
G03X808462Y1108202I180J-357D01*
G02X808679Y1104063I-1463J-2152D01*
G03X808725Y1103419I259J-305D01*
G02X809281Y1099481I-1384J-2204D01*
G03X809302Y1098926I298J-267D01*
G02X809356Y1098872I-1812J-1867D01*
G03X809642I143J140D01*
G02X809765Y1095110I1857J-1822D01*
G03X809233I-266J-299D01*
G02X805186Y1095858I-1734J1940D01*
G03X804520Y1095927I-356J-183D01*
G02X800765Y1095626I-2021J1639D01*
G37*
G36*
G01X853144Y1061451D02*
Y1061353D01*
X853138Y1061265D01*
G02X850800Y1059130I-2305J176D01*
G01X847200Y1059181D01*
G02X847266Y1063803I33J2311D01*
G01X850865Y1063752D01*
G02X853144Y1061451I-32J-2311D01*
G37*
G36*
G01X880544Y1051105D02*
Y1051007D01*
X880538Y1050919D01*
G02X875929Y1050912I-2305J177D01*
G01X875660Y1054302D01*
G02X880268Y1054668I2304J183D01*
G01X880292Y1054373D01*
X880537Y1051279D01*
G02X880544Y1051105I-2304J-180D01*
G37*
G36*
G01X868187Y1377460D02*
G02X864515Y1374811I-1591J-1664D01*
G03X863813Y1374849I-361J-171D01*
G02X863930Y1377035I-1964J1201D01*
G03X864632Y1376997I361J171D01*
G02X865094Y1377540I1963J-1202D01*
G03X865109Y1378132I-261J303D01*
G02X868202Y1378052I1591J1664D01*
G03X868187Y1377460I261J-303D01*
G37*
G54D21*
X895669Y1975079D03*
Y1801851D03*
Y1569567D03*
Y758543D03*
Y585315D03*
Y353031D03*
Y179803D03*
X167323Y1975079D03*
Y353031D03*
Y179803D03*
X68898Y190275D03*
Y17047D03*
Y595787D03*
X167323Y585315D03*
Y758543D03*
Y990827D03*
Y1569567D03*
Y1396339D03*
Y1164055D03*
X68898Y1233583D03*
X167323Y1801851D03*
G54D27*
X36500Y179000D03*
Y188500D03*
X35000Y198500D03*
X30000Y179000D03*
X23500D03*
X30000Y188500D03*
X24000D03*
X58999Y1958050D03*
X82499Y1957050D03*
X73499D03*
X66499D03*
X92499Y1959050D03*
X47499Y1915050D03*
X62999Y1914550D03*
Y1926050D03*
X81499Y1915550D03*
X47499Y1930550D03*
X62499Y1939550D03*
X73499Y1945550D03*
X83999Y1945050D03*
X167499Y43550D03*
X116400Y56000D03*
X127499Y65050D03*
X141999Y65550D03*
X156499Y66050D03*
X129999Y78050D03*
X127999Y99550D03*
X114800Y68500D03*
X97999Y199050D03*
X155999Y181050D03*
X126500Y1972400D03*
X126600Y1978500D03*
X119999Y1978550D03*
X119499Y1972550D03*
X208499Y45650D03*
X199999Y46050D03*
X225499Y46550D03*
X183499Y45550D03*
X192499Y57550D03*
X226999Y1941050D03*
X294100Y28000D03*
X563499Y1503550D03*
X748000Y357500D03*
X751499Y679148D03*
X750000Y755500D03*
X747000Y1159000D03*
X757500Y1522500D03*
X717000Y1812384D03*
X750000Y1965500D03*
X840499Y55050D03*
X839999Y46050D03*
X840999Y62550D03*
X837999Y91050D03*
X838499Y99550D03*
Y107050D03*
X839499Y119050D03*
X841499Y71550D03*
X799385Y761436D03*
X773999Y1923550D03*
X767999Y1923050D03*
X902999Y22050D03*
X917499Y21550D03*
X909499D03*
X902499Y35050D03*
X909999Y35550D03*
X916499Y36050D03*
X854499Y39550D03*
X865499D03*
X883999Y39050D03*
X904999Y67550D03*
X855499Y82050D03*
X876999D03*
X867499D03*
X845999Y111050D03*
X865499Y125550D03*
X875499D03*
X856499Y71050D03*
X881499Y70550D03*
X866999D03*
X904499Y74050D03*
X903999Y574378D03*
X866499Y724550D03*
X904814Y1789113D03*
X864414Y1940050D03*
X929999Y32550D03*
X943499Y48050D03*
Y55050D03*
X950100Y1626100D03*
X6500Y1110000D03*
Y1116500D03*
X22500Y1183000D03*
Y1176500D03*
X129400Y426900D03*
X151300Y1049300D03*
X180000Y1619600D03*
X260999Y1503550D03*
X266999Y1512550D03*
X305998Y352114D03*
X326301Y1766030D03*
X873499Y1356050D03*
G54D26*
X8499Y1937550D03*
X11703Y1951946D03*
X15750Y102250D03*
X65999Y216050D03*
X95350Y204550D03*
X89800Y208550D03*
X28100Y374000D03*
X45800Y405200D03*
X15099Y1944050D03*
X50499Y1961550D03*
X14999Y1936050D03*
X17499Y1961050D03*
X43462Y1961160D03*
X32999Y1960555D03*
X25499Y1956050D03*
X42499Y1902550D03*
X48499Y1897050D03*
X57999Y1891050D03*
X31799Y1979050D03*
X175499Y86572D03*
X176399Y94872D03*
X173500Y166315D03*
X154200Y168500D03*
X149400Y166400D03*
X186999Y99050D03*
X213499Y104650D03*
X223499Y108150D03*
X188999Y120800D03*
X233749Y110800D03*
X230749Y76300D03*
X237899Y107050D03*
X218499Y190550D03*
X247800Y269700D03*
X253871Y291410D03*
X250300Y275100D03*
X218100Y1886400D03*
X213138Y1952703D03*
X249499Y1928050D03*
X231999Y1914050D03*
X210999Y1942050D03*
X223436Y1890465D03*
X214999Y1909550D03*
X343499Y31650D03*
X308999Y87050D03*
X323400Y105200D03*
X315800Y100500D03*
X324800Y89400D03*
X293999Y293550D03*
X264499Y1964050D03*
X330500Y1966500D03*
X394199Y45050D03*
X358999Y61550D03*
X354999Y72050D03*
X371700Y85500D03*
X757499Y1079550D03*
X757999Y1484050D03*
X732549Y1806634D03*
X733149Y1798634D03*
X707600Y1815600D03*
X733049Y1814134D03*
X758499Y1893550D03*
X822100Y279500D03*
X827500Y274500D03*
X809940Y264940D03*
X822100Y261700D03*
X771105Y722789D03*
X829800Y666650D03*
X808660Y667540D03*
X820600Y664300D03*
X813200Y675900D03*
X822100Y1466800D03*
X804899Y1556950D03*
X827700Y1487600D03*
X784499Y1529050D03*
X809960Y1478040D03*
X814700Y1486300D03*
X828500Y1877800D03*
X810900Y1882440D03*
X822700Y1871100D03*
X805900Y1887560D03*
X802499Y1951550D03*
X800431Y1941193D03*
X802099Y1961950D03*
X834799Y1946950D03*
X794499Y1941050D03*
X782999Y1937050D03*
X907499Y131800D03*
X910999Y124550D03*
X916499Y172550D03*
X842499Y280924D03*
X868799Y294750D03*
X865499Y288050D03*
X867899Y321550D03*
X868299Y336150D03*
X879750Y570550D03*
X879708Y971892D03*
X886439Y1717600D03*
X862800Y1712700D03*
X889800Y1711500D03*
X917499Y1796550D03*
X873300Y1740100D03*
X863699Y1906450D03*
X857099Y1917650D03*
X938499Y115550D03*
X961499Y93350D03*
X926999Y122050D03*
X986400Y1639302D03*
X987100Y1624900D03*
X981200Y1625800D03*
X984211Y1667500D03*
X20999Y1352050D03*
Y1320550D03*
X165500Y416500D03*
X176799Y493850D03*
X246800Y677100D03*
X254499Y697700D03*
X249700Y682500D03*
X249800Y689900D03*
X238500Y680800D03*
X65599Y514250D03*
X27700Y682700D03*
X171722Y513827D03*
X163549Y517100D03*
X29000Y896500D03*
X163500Y937100D03*
X172500Y919294D03*
X108200Y963600D03*
X154749Y968249D03*
X211750Y894600D03*
X221800Y1069300D03*
X247500Y1085500D03*
X251500Y1136700D03*
X242000Y1066000D03*
X269500Y1135500D03*
X282500Y1135000D03*
X76999Y1196550D03*
X90324Y1538800D03*
X138600Y1124600D03*
X103686Y1223863D03*
X103999Y1216863D03*
X127000Y1202000D03*
X148000Y1206000D03*
X119399Y1298113D03*
X101541Y1262607D03*
X116999Y1288050D03*
X101399Y1292550D03*
X107999Y1307713D03*
X120507Y1317050D03*
X135850Y1322250D03*
X102700Y1321363D03*
X119499Y1339050D03*
X129000Y1356500D03*
X147400Y1321600D03*
X106999Y1454450D03*
X100699Y1471050D03*
X98599Y1491350D03*
X100000Y1546650D03*
X152633Y1677967D03*
X177900Y1690400D03*
X179999Y1644500D03*
X181100Y1682700D03*
X95499Y1665418D03*
X93999Y1703050D03*
X117499Y1706050D03*
X128749Y1703300D03*
X122642Y1704243D03*
X118499Y1694050D03*
X123749Y1711550D03*
X199149Y1362900D03*
X194700Y1385700D03*
X229025Y1471576D03*
X241000Y1469600D03*
X224750Y1483950D03*
X233700Y1481600D03*
X195000Y1645500D03*
X261999Y1516050D03*
X295000Y1513000D03*
X164700Y1085400D03*
X301249Y346050D03*
X825700Y1083100D03*
X807000Y1072900D03*
X825800Y1072300D03*
X815400Y1078800D03*
X803199Y1151850D03*
X864499Y1128750D03*
G54D23*
X78150Y178464D03*
X158071Y191614D03*
Y341220D03*
Y1963268D03*
X886417Y191614D03*
Y341220D03*
Y597126D03*
Y746732D03*
Y1557756D03*
Y1813662D03*
Y1963268D03*
X78150Y583976D03*
X158071Y1002638D03*
X78150Y1245394D03*
Y1395000D03*
X158071Y1152244D03*
Y1408150D03*
Y1557756D03*
X78150Y1650906D03*
X886417Y1002638D03*
Y1152244D03*
Y1408150D03*
G54D22*
X9843Y153168D03*
Y265767D03*
Y353144D03*
Y1859468D03*
Y875216D03*
Y1137420D03*
Y1250019D03*
Y1337396D03*
G54D24*
X1019291Y1416024D03*
G54D25*
X17720Y1903144D03*
X29532Y309561D03*
X271657Y267711D03*
Y1889758D03*
X994098Y149601D03*
Y673223D03*
X994099Y1068892D03*
X271657Y673223D03*
Y1078734D03*
Y1484246D03*
G54D28*
X994093Y1889751D03*
%LPD*%
G75*
G36*
G01X83251Y77848D02*
X98548Y62552D01*
Y52324D01*
G02X97995Y51954I-400J0D01*
G03X96119Y51999I-996J-2404D01*
G02X95586Y52332I-136J376D01*
G03X93879Y49601I-2587J-282D01*
G02X94412Y49268I136J-376D01*
G03X97995Y47146I2587J282D01*
G02X98548Y46776I153J-370D01*
G01Y43130D01*
G02X97981Y42767I-400J1D01*
G03X94836Y41985I-1081J-2367D01*
G02X94303Y41891I-318J243D01*
G03X94243Y41929I-1422J-2179D01*
G02X94256Y42621I207J342D01*
G03X91657Y42671I-1256J2279D01*
G02X91644Y41979I-207J-342D01*
G03X90548Y38587I1256J-2279D01*
G02X90367Y38302I-181J-85D01*
G01X90098D01*
X81700Y46699D01*
Y64052D01*
X85700Y68052D01*
Y74548D01*
X82741Y77507D01*
G02X82882Y77848I142J141D01*
G01X83251D01*
G37*
G36*
G01X92802Y37100D02*
G03X92998I98J2600D01*
G01X94881D01*
G02X95270Y36607I0J-400D01*
G03X100330I2530J-607D01*
G02X100719Y37100I389J93D01*
G01X134949D01*
X135024Y37024D01*
X137376D01*
X147350Y27050D01*
X148701D01*
X148902Y26848D01*
X257997D01*
X258198Y27050D01*
X258499D01*
X286499Y55050D01*
Y65050D01*
X290499Y69050D01*
X297999D01*
X301499Y72550D01*
Y81550D01*
X302999Y83050D01*
X316499D01*
X316999Y82550D01*
Y66050D01*
X310999Y60050D01*
X305499D01*
X263999Y18550D01*
X143095D01*
G03X139972Y20948I-3123J-835D01*
G01X139227D01*
G03X123342Y25050I-9307J-3232D01*
G01X94999D01*
X94974Y25074D01*
X89026D01*
X71499Y42601D01*
Y76050D01*
X72499Y77050D01*
X81499D01*
X84499Y74050D01*
Y68550D01*
X80499Y64550D01*
Y46201D01*
X87212Y39488D01*
G02X87072Y38831I-282J-283D01*
G03X90589Y36660I928J-2431D01*
G02X90987Y37100I398J40D01*
G01X92802D01*
G37*
G36*
G01X99749Y63050D02*
X83749Y79050D01*
X71499D01*
X70999Y79550D01*
Y86050D01*
X71499Y86550D01*
X87999D01*
X107999Y66550D01*
Y53800D01*
X108000D01*
X110100Y51700D01*
X144800D01*
X160450Y36050D01*
X252499D01*
X278499Y62050D01*
Y78050D01*
X283499Y83050D01*
X297499D01*
X297999Y82550D01*
Y72550D01*
X296499Y71050D01*
X291999D01*
X291499Y70550D01*
X287999D01*
X284999Y67550D01*
Y55550D01*
X257499Y28050D01*
X149400D01*
X138250Y39200D01*
X102900D01*
X99749Y42351D01*
Y63050D01*
G37*
G36*
G01X90999Y859550D02*
X89999Y860550D01*
Y863050D01*
X90999Y864050D01*
X136499D01*
X151499Y879050D01*
X158999D01*
X161999Y876050D01*
Y869550D01*
X160499Y868050D01*
X148999D01*
X140499Y859550D01*
X98099D01*
G03X97903I-98J-2600D01*
G01X90999D01*
G37*
G36*
G01Y888550D02*
X91399Y888950D01*
X91501Y888848D01*
X139997D01*
X140198Y889050D01*
X141999D01*
X152499Y899550D01*
X167999D01*
X168499Y899050D01*
Y893050D01*
X165499Y890050D01*
X155499D01*
X144999Y879550D01*
X92499D01*
X90999Y881050D01*
Y888550D01*
G37*
G36*
G01X88499Y856550D02*
X90399Y858450D01*
X90501Y858348D01*
X140997D01*
X141198Y858550D01*
X142499D01*
X150499Y866550D01*
X168499D01*
X169499Y865550D01*
Y860550D01*
X166999Y858050D01*
X158999D01*
X149999Y849050D01*
X89499D01*
X88499Y850050D01*
Y856550D01*
G37*
G36*
G01X92499Y894550D02*
X136499D01*
X154499Y912550D01*
X160999D01*
X161999Y911550D01*
Y905050D01*
X158999Y902050D01*
X151499D01*
X139499Y890050D01*
X91999D01*
X91499Y890550D01*
Y893550D01*
X92499Y894550D01*
G37*
G54D10*
X11999Y53550D03*
X11499Y34050D03*
X10000Y16500D03*
X11499Y142050D03*
X11999Y69050D03*
X6891Y161611D03*
X11302Y161500D03*
X7089Y166111D03*
X11500Y166000D03*
X9499Y301050D03*
Y281550D03*
X8999Y318550D03*
Y889550D03*
X8499Y979050D03*
X8999Y961550D03*
Y942050D03*
Y926550D03*
X8499Y907050D03*
X8999Y1060550D03*
Y1041050D03*
Y1025550D03*
X8499Y1006050D03*
X8999Y988550D03*
X8499Y1078050D03*
X6500Y1146000D03*
X13000Y1145500D03*
Y1151000D03*
X7000Y1151500D03*
X8799Y1302550D03*
X7499Y1282050D03*
X7999Y1264550D03*
X9399Y1347350D03*
X8299Y1320050D03*
X11299Y1850050D03*
X9099Y1881550D03*
X8499Y1979550D03*
X11500Y1987000D03*
X90899Y14850D03*
X23499Y27050D03*
X50999Y21150D03*
Y47750D03*
X27799Y38450D03*
X25799Y64050D03*
X65499Y59050D03*
Y41550D03*
Y27050D03*
X40999Y42050D03*
Y27550D03*
X17600Y5604D03*
X36000D03*
X55700Y5900D03*
X73900Y6200D03*
X90900Y5800D03*
X52499Y145050D03*
Y130550D03*
X59499Y108050D03*
Y90550D03*
Y76050D03*
X96184Y151065D03*
X71015Y123666D03*
X78165Y137116D03*
X95814Y136065D03*
X77165Y110799D03*
X15302Y161500D03*
X19500D03*
X15500Y166000D03*
X19198Y152000D03*
X19698Y166000D03*
X92899Y231450D03*
X48499Y228550D03*
X23999Y229050D03*
X52499Y162550D03*
X96184Y166065D03*
X23895Y238995D03*
X51099Y300050D03*
X90899Y309550D03*
X93199Y279650D03*
X84899Y289250D03*
X86899Y242750D03*
X75299Y261750D03*
X42999Y275650D03*
X48499Y260550D03*
Y243050D03*
X23999Y261050D03*
Y243550D03*
X52199Y342350D03*
X89899Y368350D03*
X94199Y325550D03*
X93499Y337450D03*
X95499Y355450D03*
X89999Y396450D03*
X39999Y359550D03*
Y342050D03*
Y327550D03*
X15499Y360050D03*
Y342550D03*
Y328050D03*
X94500Y456800D03*
X75300Y454100D03*
X67300Y450200D03*
X68899Y445450D03*
X87599Y403950D03*
X76099Y414250D03*
X95399Y416350D03*
X89099Y426150D03*
X93499Y481550D03*
Y477050D03*
X93199Y449850D03*
X93500Y445300D03*
X62055Y561550D03*
X75999Y556640D03*
X70800Y540300D03*
X77165Y514650D03*
X94499Y486550D03*
X52333Y641295D03*
X72599Y578236D03*
X39999Y576550D03*
X61099Y603236D03*
X93599Y581236D03*
X92599Y606236D03*
X93100Y571640D03*
X47800Y692800D03*
X53210Y701486D03*
X43499Y657550D03*
X39899Y754850D03*
X39399Y768750D03*
X27199Y764950D03*
X28599Y775450D03*
X26399Y750850D03*
X79900Y791300D03*
X67999Y790400D03*
X53999Y791000D03*
X93299Y862050D03*
X26799Y874550D03*
X26099Y891650D03*
X76399Y820450D03*
X70100Y818900D03*
X93690Y887139D03*
X93900Y882400D03*
X94001Y856895D03*
X93808Y852063D03*
X93499Y892050D03*
X25699Y916150D03*
X25099Y942150D03*
X23899Y957950D03*
X93499Y897152D03*
X93000Y907165D03*
X77499Y921550D03*
X77002Y952079D03*
X76711Y948089D03*
X77499Y962152D03*
X83988Y934028D03*
X24799Y992250D03*
X33899Y1005950D03*
X65799Y994050D03*
X72799Y982950D03*
X86900Y981600D03*
X21500Y1122500D03*
Y1092500D03*
X17500D03*
X18000Y1145500D03*
X17500Y1150500D03*
X22447Y1223247D03*
X23200Y1209300D03*
X21299Y1300250D03*
X21799Y1282750D03*
X22321Y1231121D03*
X18099Y1343550D03*
X96000Y1369000D03*
X96100Y1384650D03*
X77166Y1353400D03*
X93316Y1351000D03*
X77165Y1327335D03*
X76499Y1507050D03*
Y1498050D03*
Y1512050D03*
Y1503050D03*
X76999Y1528050D03*
Y1519050D03*
X90999Y1628550D03*
Y1624550D03*
X91121Y1632549D03*
X86299Y1632550D03*
X85999Y1628550D03*
Y1624550D03*
X84099Y1737150D03*
X83599Y1744750D03*
X77165Y1759550D03*
X93499D03*
X94336Y1773113D03*
X78529Y1788113D03*
X38600Y1880200D03*
X31400Y1885200D03*
X30400Y1849650D03*
X23999Y1857950D03*
X27199Y1874350D03*
X52999Y1871550D03*
X57499Y1871050D03*
X36100Y1892200D03*
X79500Y1987500D03*
X61500D03*
X44500Y1987000D03*
X26500D03*
X55999Y1982550D03*
X157299Y5150D03*
X107000Y6000D03*
X169300Y130300D03*
X178700Y129900D03*
X152999Y141050D03*
X123499Y149050D03*
X133999D03*
X142999Y141050D03*
X132999Y141550D03*
X176499Y140050D03*
X167499Y149550D03*
X144499Y149050D03*
X163499Y140050D03*
X160999Y149550D03*
X123499Y140050D03*
X177899Y199250D03*
X117500Y162300D03*
X124300Y167800D03*
X131799Y201950D03*
X142688Y218861D03*
X143110Y203861D03*
X135399Y277050D03*
X130799Y300250D03*
X158999Y259800D03*
X152808Y246341D03*
X166800Y240800D03*
X133000Y240500D03*
X157740Y273924D03*
X139399Y372350D03*
X167299Y369350D03*
X130099Y326150D03*
X134699Y356050D03*
X126099Y396150D03*
X152499Y395950D03*
X135999Y472550D03*
X135140Y478930D03*
X100500Y456700D03*
X99399Y437450D03*
X124899Y409050D03*
X133499Y445050D03*
X128999Y445550D03*
X97699Y477050D03*
Y481550D03*
X149700Y471600D03*
X154100Y476500D03*
X164600Y476700D03*
X171300D03*
X97999Y445550D03*
X97699Y449850D03*
X108599Y557236D03*
X154099Y529236D03*
X101500Y536500D03*
X139200Y484300D03*
X134499Y488050D03*
X145649Y509550D03*
X136349Y509050D03*
X98999Y488050D03*
X140499Y499050D03*
X153499Y502550D03*
X148999D03*
X136299Y499050D03*
X108900Y587600D03*
X162500Y623400D03*
X140000Y587700D03*
X140499Y600550D03*
X152400Y643300D03*
X140499Y626050D03*
X143999Y605550D03*
X170799Y689150D03*
X171999Y672450D03*
X131099Y700450D03*
X139099Y707150D03*
X152124Y651868D03*
X159054Y665400D03*
X110800Y772700D03*
X178899Y765250D03*
X172599Y774250D03*
X161999Y768050D03*
X156499Y876050D03*
Y870550D03*
X97499Y862050D03*
X172099Y877450D03*
X168499Y846713D03*
X173899Y846550D03*
X161999Y843550D03*
Y848050D03*
X156499Y846050D03*
X156999Y850050D03*
X158114Y883290D03*
X156499Y886950D03*
X155499Y891050D03*
Y896050D03*
X97700Y887400D03*
X97900Y882400D03*
X163999Y863050D03*
X159999D03*
X155999Y859050D03*
Y863050D03*
X97800Y851800D03*
X98001Y856950D03*
X97499Y892550D03*
X109500Y901100D03*
X153299Y943750D03*
X106500Y943000D03*
X105300Y960300D03*
X169299Y956350D03*
X159459Y896616D03*
X163499Y896550D03*
X157499Y909050D03*
Y904550D03*
X159186Y946117D03*
X171499Y998650D03*
X156499Y985950D03*
X149499Y997650D03*
X162499Y1023550D03*
X163499Y1035050D03*
X158300Y1015000D03*
X141234Y1029885D03*
X140864Y1044885D03*
X159499Y1044579D03*
X165600Y1057428D03*
X137900Y1103400D03*
X139100Y1097100D03*
X169299Y1067150D03*
X168099Y1083550D03*
X167999Y1092850D03*
X143200Y1116300D03*
X134500Y1108100D03*
X171599Y1139950D03*
X167499Y1118550D03*
X167999Y1130550D03*
X133200Y1132100D03*
X164999Y1075550D03*
X159055Y1070400D03*
X106999Y1114960D03*
X145900Y1163200D03*
X163499Y1171650D03*
X151699Y1158550D03*
X144399Y1171150D03*
X150999Y1181150D03*
X141499Y1185550D03*
X151499Y1173050D03*
X121657Y1224604D03*
X120999Y1188050D03*
X111999D03*
X102999D03*
X128400Y1188600D03*
X104999Y1231050D03*
X100999Y1231032D03*
X120999Y1228550D03*
X120499Y1264550D03*
X126499D03*
X123938Y1267623D03*
X103499Y1305050D03*
X117149Y1267550D03*
X175499Y1306113D03*
X145999Y1353050D03*
X167499Y1389050D03*
X156999Y1397750D03*
X143199Y1412050D03*
X163499Y1433350D03*
X166799Y1409350D03*
X178200Y1393400D03*
X176599Y1447450D03*
X172299Y1465850D03*
X165499Y1453550D03*
X157915Y1420460D03*
X140799Y1435460D03*
X166799Y1487450D03*
X176299Y1500150D03*
X159054Y1476200D03*
X124999Y1616050D03*
Y1620050D03*
Y1629050D03*
Y1633050D03*
X119999Y1629050D03*
X120100Y1633100D03*
X122499Y1668550D03*
Y1672550D03*
X126562Y1670613D03*
X118999Y1670550D03*
X157500Y1797400D03*
X126599Y1789650D03*
X120299Y1796150D03*
X142144Y1801644D03*
X104417Y1791480D03*
X144499Y1745550D03*
X137999Y1747723D03*
X129999Y1747050D03*
X123499D03*
X117499Y1745050D03*
X97999Y1815050D03*
X104500Y1813400D03*
X173899Y1813250D03*
X177599Y1866750D03*
X168299Y1879850D03*
X168499Y1855550D03*
X127499Y1889050D03*
X126999Y1882550D03*
X111499Y1877550D03*
Y1882550D03*
X122999Y1883050D03*
X115999Y1882550D03*
X157999Y1840972D03*
X158000Y1825400D03*
X159054Y1881800D03*
X167200Y1868000D03*
X159054Y1855050D03*
X116499Y1877550D03*
X122999Y1889050D03*
X168899Y1960750D03*
X163599Y1892050D03*
X159173Y1935972D03*
X142499Y1905972D03*
X141499Y1895972D03*
X98000Y1987500D03*
X163500D03*
X146000D03*
X128500D03*
X115000Y1987000D03*
X246200Y65800D03*
X246000Y61300D03*
Y56500D03*
Y52100D03*
X245600Y43800D03*
X245500Y39100D03*
X247100Y47900D03*
X189499Y4550D03*
X206999Y5050D03*
X226499D03*
X241999D03*
X261499Y4550D03*
X246000Y70800D03*
X244900Y149100D03*
X244499Y136550D03*
Y122050D03*
X229099Y161350D03*
X206899Y171650D03*
X190199Y178650D03*
X232400Y220700D03*
X210999Y221550D03*
X191999D03*
X249800Y248800D03*
X235399Y263350D03*
X201199Y266750D03*
X181299Y267350D03*
X217999Y250550D03*
X203499D03*
X185999D03*
X187199Y359050D03*
X223799Y365350D03*
X209199Y365050D03*
X181599Y396250D03*
X217599Y396450D03*
X258999Y396650D03*
X209999Y426150D03*
X237699Y426050D03*
X218499Y474850D03*
X251499Y446050D03*
X231999Y445550D03*
X251999Y462050D03*
X232499Y461550D03*
X209499Y412550D03*
X220000Y421000D03*
X232999Y414550D03*
X252499Y415050D03*
X244199Y483350D03*
X224299Y494650D03*
X242099Y511750D03*
X244999Y559550D03*
Y545050D03*
X220499Y560050D03*
Y545550D03*
X257499Y530050D03*
Y512550D03*
Y498050D03*
X205300Y508100D03*
X190499Y507513D03*
X257199Y640050D03*
X224999Y613450D03*
X256499Y609050D03*
Y591550D03*
Y577050D03*
X245000Y647000D03*
X244499Y632050D03*
X219999Y647050D03*
Y632550D03*
X207300Y639400D03*
X206499Y623550D03*
Y609050D03*
X181999Y641550D03*
Y624050D03*
Y609550D03*
X244999Y577050D03*
X220499Y577550D03*
X199199Y659150D03*
X234200Y668300D03*
X226399Y677550D03*
X212999Y677350D03*
X190399Y689050D03*
X182599Y688350D03*
X246500Y663300D03*
X218800Y668700D03*
X224099Y770250D03*
X209500Y759000D03*
X208799Y766750D03*
X214799Y774750D03*
X245599Y773450D03*
X234299Y773750D03*
X247099Y795050D03*
X227199D03*
X197099D03*
X254699Y807650D03*
X233799Y806350D03*
X208299Y805350D03*
X198199Y805950D03*
X190699Y778350D03*
X244099Y857450D03*
X245199Y878050D03*
X232399Y886550D03*
X252899Y886350D03*
X252399Y838250D03*
X245399Y823550D03*
X217300Y816800D03*
X198499Y884113D03*
X245399Y907450D03*
X243899Y923650D03*
X242199Y938750D03*
X256199Y916250D03*
X254899Y929250D03*
X253499Y938050D03*
X252499Y948850D03*
X244199Y973250D03*
X225299Y957650D03*
X213999Y958650D03*
X206699Y953050D03*
X203999Y943350D03*
X204699Y929450D03*
X205999Y978250D03*
X256499Y967050D03*
X233499Y966050D03*
X216999Y967550D03*
X254499Y984550D03*
X245899Y995250D03*
X232299Y981950D03*
X206299Y990250D03*
X207299Y1008150D03*
X202100Y1028100D03*
X253999Y1052050D03*
X253499Y1038550D03*
X232499Y1038050D03*
X216499Y1053050D03*
X215999Y1039550D03*
X258999Y1011550D03*
X233999Y1012550D03*
Y997050D03*
X217999Y1012050D03*
X217499Y998550D03*
Y981050D03*
X199499Y1093850D03*
X209900Y1093600D03*
X249499Y1104150D03*
X260349Y1139200D03*
X214499Y1154250D03*
X223099Y1182750D03*
X210199Y1173450D03*
X204199Y1163850D03*
X208199Y1145850D03*
X180400Y1202800D03*
X201600Y1205900D03*
X220999Y1224350D03*
X242199Y1210050D03*
X242599Y1198350D03*
X232599Y1195750D03*
X247899Y1208650D03*
X251999Y1184550D03*
X212499Y1212550D03*
X181700Y1219900D03*
X212499Y1184550D03*
X196499Y1224550D03*
Y1215550D03*
Y1196550D03*
X202199Y1276850D03*
X202899Y1291450D03*
X179500Y1262000D03*
X179800Y1244100D03*
X196399Y1236650D03*
X221599Y1237250D03*
X222299Y1251850D03*
X229899Y1250550D03*
X216300Y1274800D03*
X234299Y1232650D03*
X261199Y1227950D03*
X250900Y1248500D03*
X242900Y1263000D03*
X232799Y1276150D03*
X254899Y1289950D03*
X241399Y1303250D03*
X211499Y1267050D03*
Y1258050D03*
Y1239050D03*
X195499Y1279050D03*
Y1270050D03*
Y1251050D03*
X239099Y1314150D03*
X252399Y1326350D03*
X219099Y1325950D03*
X226599Y1340250D03*
X207699Y1337950D03*
X195500Y1352500D03*
X213199Y1350050D03*
X227399Y1363050D03*
X234300Y1375700D03*
X217499Y1387450D03*
X249800Y1388400D03*
X245999Y1358050D03*
X246499Y1370050D03*
X245999Y1339050D03*
X208049Y1385550D03*
X258999Y1396950D03*
X230599Y1400250D03*
X217999Y1408850D03*
X204699Y1418350D03*
X203199Y1393250D03*
X201000Y1408500D03*
X180599Y1424050D03*
X180000Y1439500D03*
X204999Y1472650D03*
X250199Y1473550D03*
X226300Y1447800D03*
X230899Y1437350D03*
X238899Y1453750D03*
X259299Y1438750D03*
X227999Y1421550D03*
X212400Y1433700D03*
X194200Y1457900D03*
X244999Y1412550D03*
X245499Y1424550D03*
X181500Y1479000D03*
X202399Y1500750D03*
X208999Y1491250D03*
X247500Y1499000D03*
X248000Y1482000D03*
X212899Y1535550D03*
X230999D03*
X213399Y1500300D03*
X236999Y1535550D03*
X246200Y1617600D03*
X239400Y1624300D03*
X218000Y1614300D03*
X209200Y1624000D03*
X228999Y1637550D03*
X211999Y1568550D03*
X238300Y1575100D03*
X231499Y1575050D03*
X224499D03*
X217999Y1574550D03*
X211999D03*
X258700Y1645100D03*
X237400Y1663800D03*
X230600Y1670500D03*
X197600Y1694900D03*
X204400Y1688200D03*
X216601Y1684350D03*
X226800Y1684200D03*
X220100Y1691700D03*
X209901Y1691850D03*
X212000Y1701300D03*
X201801Y1701450D03*
X195001Y1708150D03*
X205200Y1708000D03*
X180701Y1716050D03*
X195500Y1717000D03*
X200600Y1663600D03*
X199900Y1670600D03*
X213000Y1672500D03*
X181900Y1675300D03*
X255699Y1722550D03*
X222700Y1710100D03*
X242999Y1658050D03*
X193499Y1674050D03*
X253999Y1676550D03*
X235499Y1697050D03*
X256499Y1710050D03*
X180000Y1731000D03*
X179701Y1724550D03*
X195000Y1725500D03*
X249199Y1743150D03*
X222499Y1743850D03*
X259499Y1760650D03*
X221499Y1760950D03*
X199699Y1761450D03*
X220799Y1791550D03*
X252199Y1793050D03*
X238699Y1801850D03*
X205199Y1801950D03*
X182299Y1801350D03*
X206900Y1726700D03*
X185999Y1746050D03*
X237999Y1730550D03*
X244999Y1755050D03*
X253899Y1813250D03*
X215299Y1813950D03*
X255999Y1855950D03*
X204399Y1855450D03*
X206999Y1867550D03*
X241199Y1867150D03*
X244700Y1878700D03*
X224800Y1867000D03*
X212399Y1885850D03*
X199599Y1879850D03*
X181099Y1885850D03*
X261499Y1825050D03*
X209999D03*
X192100Y1813500D03*
X228999Y1856050D03*
X241255Y1896055D03*
X205499Y1968650D03*
X183999Y1968150D03*
X190399Y1961250D03*
X207199Y1892850D03*
X191599Y1891550D03*
X238999Y1970550D03*
X232999Y1971050D03*
X227499D03*
X221300Y1971200D03*
X240900Y1979000D03*
X225199Y1978750D03*
X209699D03*
X188199Y1978250D03*
X254500Y1987500D03*
X236500D03*
X216999Y1987550D03*
X199000Y1987500D03*
X183000D03*
X199600Y1974900D03*
X278999Y5050D03*
X292999Y4550D03*
X310499Y5050D03*
X329999D03*
X306999Y55450D03*
X311299D03*
X315799Y55350D03*
X290999Y67550D03*
X306100Y126500D03*
X332200Y94200D03*
X283599Y106250D03*
X274700Y131500D03*
X280999Y120050D03*
X289999Y72550D03*
X288499Y76550D03*
X289499Y80550D03*
X308499Y72550D03*
X303999Y74050D03*
X307999Y78550D03*
X343799Y204550D03*
X321799Y173950D03*
X343399Y161350D03*
X307199Y205550D03*
X317499Y192950D03*
X331499Y193250D03*
X262699Y208550D03*
X262299Y164050D03*
X280999Y152050D03*
X343999Y190050D03*
X337999Y219050D03*
X310499Y216550D03*
X290999Y216050D03*
X271999D03*
X325499Y249450D03*
X313199Y270350D03*
X297999Y245050D03*
X283499D03*
X265999D03*
X343499Y253550D03*
X337499Y282550D03*
X313000Y313900D03*
X316999Y312576D03*
X276299Y376050D03*
X299899Y376650D03*
X328799Y372350D03*
X339399Y358050D03*
X289399Y395750D03*
X310999Y396250D03*
X338399Y395650D03*
X321748Y343299D03*
X277799Y338599D03*
X266699Y425050D03*
X336099Y417550D03*
X322099Y426850D03*
X338899Y433850D03*
X300899Y431850D03*
X328599Y442250D03*
X291599Y446150D03*
X266199Y472350D03*
X327900Y463200D03*
X306100Y462000D03*
X286999Y462050D03*
X272499Y445050D03*
X272999Y461050D03*
X269999Y415050D03*
X284499D03*
X303999Y415550D03*
X324999Y414550D03*
X277999Y545350D03*
X329999Y510450D03*
X298599Y501250D03*
X309399Y513450D03*
X321999Y533150D03*
X297599Y519350D03*
X340799Y512050D03*
X341399Y535850D03*
Y558950D03*
X331999Y555050D03*
Y540550D03*
X307499Y555550D03*
Y541050D03*
X281999Y529550D03*
Y512050D03*
Y497550D03*
X321999Y550550D03*
X297499Y551050D03*
X333499Y483050D03*
X312499Y484050D03*
X292999Y483550D03*
X321299Y565250D03*
X296199Y568550D03*
X320799Y582050D03*
X340299Y586550D03*
X342199Y613050D03*
X328599Y602450D03*
X302899Y607950D03*
X328499Y635650D03*
X317999Y627850D03*
X342099Y646350D03*
X280999Y608550D03*
Y591050D03*
Y576550D03*
X331999Y572550D03*
X307499Y573050D03*
X331999Y646550D03*
X307499Y647050D03*
X293999Y630550D03*
Y616050D03*
X269499Y631050D03*
Y616550D03*
X341899Y664950D03*
X342599Y678850D03*
X341399Y715050D03*
X330799Y712450D03*
X324599Y696150D03*
X297699Y681850D03*
X296399Y716950D03*
X308899Y705150D03*
X298399Y703450D03*
X331999Y678550D03*
Y661050D03*
X307499Y679050D03*
Y661550D03*
X293999Y648050D03*
X269499Y648550D03*
X338099Y811650D03*
X307999Y803150D03*
X307899Y794550D03*
X287799Y794850D03*
X268099Y795450D03*
X275299Y806350D03*
X315000Y754500D03*
X338599Y821650D03*
X318999Y814350D03*
X338599Y840450D03*
X325599Y823950D03*
X283599Y857450D03*
X293899Y843850D03*
X304899Y856150D03*
X315199Y869450D03*
X323099Y885050D03*
X340099Y887350D03*
X330299Y871850D03*
X323799Y859850D03*
X313499Y847850D03*
X300199Y835250D03*
X288899Y820550D03*
X264999Y858450D03*
X280999Y843050D03*
Y827550D03*
X264999Y842550D03*
X264499Y829050D03*
X297499Y884050D03*
Y868550D03*
X281499Y883550D03*
X280999Y870050D03*
X265799Y901850D03*
X274299Y912950D03*
X310699Y943550D03*
X323499Y956950D03*
X329799Y970650D03*
X331099Y923650D03*
X322099Y913650D03*
X302499Y899050D03*
X321099Y899650D03*
X338399Y901050D03*
X340099Y910350D03*
X340399Y931250D03*
X340099Y952850D03*
X328099Y937250D03*
X315199Y925950D03*
X302199Y914650D03*
X287299Y901050D03*
X269599Y923950D03*
X267199Y935350D03*
X264799Y946850D03*
X263299Y959350D03*
X281099Y943550D03*
X278799Y956150D03*
X277599Y975250D03*
X290099Y948650D03*
X289399Y963350D03*
X288099Y971250D03*
X299399Y965950D03*
X298099Y977250D03*
X307999Y970650D03*
X272999Y965550D03*
X333099Y983450D03*
X285399Y982950D03*
X294699Y989550D03*
X306699Y981250D03*
X304399Y997550D03*
X320999Y997250D03*
X331299Y1017150D03*
X331599Y1028750D03*
X329599Y1040750D03*
X321299Y1012450D03*
Y1024750D03*
X318299Y1038750D03*
X329599Y1057050D03*
X317699Y1054650D03*
X299999Y1052350D03*
X289699Y1021750D03*
X298399Y1008150D03*
X287099Y1000150D03*
X306399Y1020750D03*
X303699Y1038050D03*
X304699Y1057050D03*
X287099Y1035050D03*
X275099Y1024750D03*
X262499Y995850D03*
X269999Y1052550D03*
Y1037050D03*
X274999Y1012050D03*
Y996550D03*
X272999Y981050D03*
X339599Y1081550D03*
X319999Y1066950D03*
X274900Y1115600D03*
X262499Y1129150D03*
X272999Y1102850D03*
X312299Y1093550D03*
X276299Y1134550D03*
X290699Y1122650D03*
X329299Y1098550D03*
X326599Y1112350D03*
X307999Y1142050D03*
X299499Y1113550D03*
Y1098050D03*
X283499Y1113050D03*
X282999Y1099550D03*
X332999Y1138550D03*
Y1123050D03*
X317999Y1137550D03*
X316499Y1124550D03*
X283299Y1144850D03*
X323999Y1153250D03*
X304499Y1156650D03*
X313499Y1170150D03*
X291399Y1174150D03*
X300699Y1185150D03*
X279799Y1191750D03*
X286599Y1203750D03*
X315408Y1202663D03*
X329799Y1182750D03*
X311999Y1213850D03*
X300699Y1227350D03*
X272999Y1214150D03*
X326649Y1218850D03*
X328999Y1200550D03*
X310299Y1240050D03*
X264800Y1261300D03*
X283799Y1249250D03*
X304699Y1265850D03*
X312499Y1280350D03*
X300499Y1305350D03*
X274299Y1276450D03*
X295399Y1292950D03*
X281099Y1302850D03*
X333349Y1288900D03*
Y1270500D03*
X327999Y1255050D03*
X326649Y1227850D03*
X311500Y1316300D03*
X264799Y1313850D03*
X286799Y1326450D03*
X297899Y1336150D03*
X298099Y1357250D03*
X265299Y1339650D03*
X263699Y1359550D03*
X301699Y1377950D03*
X278799Y1386250D03*
X265499Y1376950D03*
X313600Y1391300D03*
X312900Y1366900D03*
X311900Y1344900D03*
X286499Y1364050D03*
Y1345050D03*
X301699Y1395750D03*
X268499Y1453550D03*
X278000Y1422000D03*
X270599Y1408550D03*
X303499Y1411250D03*
X300899Y1433350D03*
X286600Y1449700D03*
X304699Y1457550D03*
X313600Y1442700D03*
X312800Y1467400D03*
X312100Y1420700D03*
X285499Y1418550D03*
Y1427550D03*
Y1399550D03*
X296599Y1497150D03*
X312000Y1514600D03*
X286700Y1516100D03*
X307000Y1619600D03*
X278499Y1621550D03*
X265700Y1635100D03*
X289000Y1641800D03*
X320299Y1642950D03*
X316799Y1657450D03*
X302399Y1662950D03*
X284300Y1676900D03*
X329999Y1716950D03*
X291099Y1707450D03*
X318499Y1675550D03*
X299999Y1696050D03*
X270999Y1660550D03*
X273499Y1694050D03*
X280499Y1718550D03*
X320999Y1706050D03*
X303999Y1722050D03*
X343899Y1752650D03*
X297099Y1733850D03*
X270599Y1748950D03*
X290699Y1760750D03*
X286599Y1791850D03*
X327299D03*
X322299Y1802150D03*
X303999Y1800850D03*
X270599Y1801450D03*
X263499Y1734550D03*
X285499Y1742550D03*
X321999Y1733050D03*
X303499Y1753550D03*
X321499Y1772550D03*
X315499Y1812250D03*
X284299Y1811150D03*
X270299Y1867250D03*
X337499Y1855950D03*
X316999D03*
X298999D03*
X308099Y1880550D03*
X295299Y1870250D03*
X313599Y1889250D03*
Y1870250D03*
X326399Y1876250D03*
X336799Y1888950D03*
Y1869950D03*
X283999Y1856050D03*
X314099Y1901250D03*
X326899Y1907250D03*
X326399Y1895250D03*
X335799Y1916450D03*
X336799Y1897950D03*
X305999Y1913050D03*
X302499Y1922050D03*
X296858Y1956228D03*
X326799Y1977050D03*
X329999Y1987550D03*
X311500Y1987500D03*
X291499Y1987550D03*
X272000Y1987500D03*
X416999Y25050D03*
X417499Y46550D03*
X416999Y63550D03*
X345499Y5050D03*
X364999Y4550D03*
X382499Y5050D03*
X395999Y5550D03*
X413499Y6050D03*
X381299Y136750D03*
X389599Y90950D03*
X400499Y134050D03*
Y119550D03*
X363999Y136050D03*
X417499Y79050D03*
Y93550D03*
Y108050D03*
Y125550D03*
X416999Y145050D03*
X387599Y220150D03*
X385999Y207250D03*
X354099Y175350D03*
X389299Y161650D03*
X400499Y151550D03*
X363999Y153550D03*
X369999Y219050D03*
X382499Y190550D03*
X355499Y219050D03*
X362999Y190050D03*
X416999Y164050D03*
X417999Y185050D03*
X423799Y259750D03*
X383299Y310250D03*
X386899Y299250D03*
X359399Y307250D03*
X347399Y301950D03*
X355999Y242750D03*
X347699Y269050D03*
X382999Y276650D03*
X412999Y307550D03*
Y290050D03*
Y275550D03*
X369499Y282550D03*
X381999Y254050D03*
X354999Y282550D03*
X362499Y253550D03*
X354099Y373050D03*
X368299Y386350D03*
X357999Y359050D03*
X380599Y381050D03*
X386599Y348450D03*
X394899Y357750D03*
X422499Y348150D03*
X422199Y363350D03*
X420199Y391350D03*
X419599Y458550D03*
X426599Y415350D03*
X415099Y422550D03*
X410799Y431150D03*
X354699Y426650D03*
X356399Y451750D03*
X351399Y470750D03*
X358399Y498650D03*
X357399Y521250D03*
Y530550D03*
Y543850D03*
X357999Y559450D03*
X415999Y518550D03*
X420199Y638550D03*
X427499Y624550D03*
X359399Y576050D03*
Y599650D03*
X360399Y615550D03*
X359699Y627550D03*
X345399Y698950D03*
X358899Y657150D03*
X359399Y669450D03*
X359199Y690650D03*
X357699Y707750D03*
X353999Y787750D03*
X347699Y773450D03*
X355999Y752850D03*
X424999Y766550D03*
X422999Y785050D03*
Y799550D03*
X418799Y896050D03*
Y877050D03*
X422499Y855550D03*
Y836550D03*
X422999Y817050D03*
X424299Y1034050D03*
X423299Y1013050D03*
Y994050D03*
X419999Y1115550D03*
X409499Y1102550D03*
X416099Y1183550D03*
X415499Y1176050D03*
Y1161550D03*
X419499Y1219550D03*
X420099Y1241550D03*
X419499Y1234050D03*
X424999Y1278550D03*
X425499Y1290550D03*
X424999Y1259550D03*
X416699Y1342650D03*
X416199Y1367550D03*
X423299Y1430350D03*
X426799Y1416050D03*
X422299Y1394950D03*
X425799Y1447950D03*
X427099Y1469150D03*
X414799Y1532350D03*
X424299Y1541350D03*
X415999Y1603250D03*
X416199Y1625250D03*
X425499Y1635050D03*
X418299Y1561250D03*
X414799Y1653750D03*
X414399Y1678350D03*
X414499Y1707250D03*
X427499Y1662050D03*
X417799Y1790850D03*
X387899Y1802850D03*
X359499Y1736850D03*
X393499Y1759550D03*
X376499Y1775550D03*
X357999Y1796050D03*
X410757Y1772872D03*
X393999Y1784550D03*
X422999Y1778550D03*
X414499Y1810450D03*
X355699Y1810750D03*
X426499Y1855450D03*
X406999Y1855950D03*
X391499D03*
X369499D03*
X351999Y1855450D03*
X359999Y1878550D03*
X421399Y1888050D03*
X369799Y1880050D03*
X389499Y1885050D03*
X348999Y1879050D03*
X406499Y1874050D03*
X367299Y1956950D03*
X358999Y1925050D03*
X359999Y1897550D03*
Y1906550D03*
X420399Y1962550D03*
Y1934550D03*
Y1953550D03*
X421399Y1916050D03*
Y1907050D03*
X347699Y1972250D03*
X367999Y1940250D03*
X369199Y1919750D03*
X369999Y1901950D03*
X388499Y1959550D03*
Y1950550D03*
Y1932950D03*
X389499Y1913050D03*
Y1904050D03*
X349499Y1910050D03*
X348499Y1956550D03*
X347999Y1944550D03*
Y1925550D03*
X348999Y1898050D03*
X406999Y1905050D03*
X405999Y1951550D03*
X405499Y1939550D03*
Y1920550D03*
X406499Y1893050D03*
X385099Y1975950D03*
X420799Y1977250D03*
X399299Y1976750D03*
X367299Y1972950D03*
X420500Y1987000D03*
X403500D03*
X364999Y1987050D03*
X382499Y1987550D03*
X345499D03*
X436499Y50350D03*
Y31350D03*
X466799Y64750D03*
X465799Y43750D03*
Y24750D03*
X499999Y64050D03*
X500499Y47050D03*
X499999Y25550D03*
X432999Y6050D03*
X448499D03*
X467999Y5550D03*
X485499Y6050D03*
X498999D03*
X437499Y71350D03*
X442799Y142450D03*
X441799Y121450D03*
Y102450D03*
X471399Y124550D03*
X470399Y103550D03*
Y84550D03*
X473099Y141050D03*
X499999Y145550D03*
X500499Y126050D03*
Y108550D03*
Y79550D03*
Y94050D03*
X502899Y217150D03*
X504199Y193250D03*
X472999Y214550D03*
X483599Y179350D03*
X446799Y205650D03*
X445799Y184650D03*
Y165650D03*
X474099Y181050D03*
X473099Y160050D03*
X449999Y217050D03*
X430499D03*
X499999Y164550D03*
X466399Y304950D03*
X479299Y297250D03*
X437499Y307050D03*
Y289550D03*
Y275050D03*
X444499Y283050D03*
X463999Y283550D03*
X481499D03*
X495999D03*
X448999Y255550D03*
X469999Y254550D03*
X508499Y255050D03*
X488999Y254550D03*
X438999Y381550D03*
X458499Y382050D03*
X484900Y394700D03*
X485000Y373200D03*
X509999Y382550D03*
X443499Y354050D03*
X464499Y353050D03*
X502999Y353550D03*
X483499Y353050D03*
X498399Y470050D03*
X503699Y419250D03*
X472499Y458050D03*
X468799Y414250D03*
X443199Y440850D03*
X440099Y459250D03*
X431099Y479350D03*
X450300Y404200D03*
X490499Y464050D03*
X490999Y444550D03*
Y427050D03*
Y412550D03*
X454499Y472550D03*
X454999Y438550D03*
X454499Y458050D03*
X453999Y417550D03*
X430099Y551450D03*
X485299Y534550D03*
X508699Y498950D03*
X471499Y493950D03*
X452499Y565050D03*
X456499Y518050D03*
X435499Y519050D03*
X491499Y504050D03*
X490499Y483050D03*
X453999Y509550D03*
X454499Y490050D03*
X504499Y598050D03*
Y580550D03*
Y566050D03*
X479999Y598550D03*
Y581050D03*
Y566550D03*
X509999Y640550D03*
X452499Y597050D03*
Y579550D03*
X427999Y597550D03*
Y580050D03*
Y565550D03*
X506599Y711650D03*
X487299Y716950D03*
X451099Y711650D03*
X450399Y672750D03*
X444799Y687350D03*
X509999Y672550D03*
Y655050D03*
X488499Y691050D03*
Y673550D03*
Y659050D03*
X463999Y691550D03*
Y674050D03*
Y659550D03*
X467699Y772750D03*
X468699Y788350D03*
X472999Y736550D03*
X489599Y752450D03*
X490299Y734550D03*
X453399Y807950D03*
X452099Y781450D03*
Y762450D03*
X435299Y795150D03*
Y777650D03*
Y763150D03*
X437299Y744650D03*
X495999Y795050D03*
X475699Y880450D03*
X479599Y847550D03*
X462999Y884050D03*
Y865050D03*
X453399Y826950D03*
X434799Y833650D03*
Y814650D03*
X464499Y896050D03*
X493499Y884050D03*
Y865050D03*
X493999Y845550D03*
Y813550D03*
Y828050D03*
X506899Y919950D03*
Y900950D03*
X443599Y945650D03*
X442599Y924650D03*
Y905650D03*
X486799Y941050D03*
X485799Y920050D03*
Y901050D03*
X461999Y966050D03*
X462499Y946550D03*
Y914550D03*
Y929050D03*
X494099Y1017350D03*
X493099Y996350D03*
X462499Y1043850D03*
X461999Y985050D03*
X474499Y1115050D03*
X491999Y1115550D03*
X454999D03*
X439499D03*
X501499Y1102550D03*
X463999Y1102050D03*
X481499Y1102550D03*
X444499D03*
X428999D03*
X436999Y1142550D03*
Y1128050D03*
X504399Y1132250D03*
X473099Y1144550D03*
X453499Y1140550D03*
X484499Y1085850D03*
X483499Y1064850D03*
X433599Y1085550D03*
X432599Y1064550D03*
X463499Y1083850D03*
X462499Y1062850D03*
X437599Y1150050D03*
X487099Y1218050D03*
X486499Y1210550D03*
Y1196050D03*
X443199Y1224250D03*
X507199Y1224350D03*
X506599Y1202350D03*
Y1216850D03*
X505399Y1153250D03*
X474099Y1165550D03*
X454499Y1161550D03*
X443799Y1274250D03*
Y1246250D03*
Y1265250D03*
X443199Y1238750D03*
X507199Y1252350D03*
Y1243350D03*
X465499Y1284550D03*
Y1293550D03*
Y1265550D03*
X498299Y1323350D03*
X468999Y1323950D03*
X428499Y1325350D03*
X508599Y1370550D03*
X444899Y1377950D03*
X434499Y1360250D03*
X448099Y1341250D03*
X473999Y1342450D03*
X485599Y1367550D03*
X468699Y1362850D03*
X466699Y1378150D03*
X498899Y1386450D03*
X499199Y1350550D03*
X459699Y1468050D03*
X464199Y1401450D03*
X459999Y1424050D03*
X498899Y1408350D03*
X500899Y1434350D03*
X505899Y1466250D03*
X482599Y1449950D03*
X456399Y1445950D03*
X445099Y1464250D03*
X478299Y1464850D03*
X481499Y1417050D03*
Y1402550D03*
X441499Y1431550D03*
Y1414050D03*
Y1399550D03*
X499699Y1538950D03*
X466999Y1530650D03*
X488299Y1531050D03*
X461399Y1541650D03*
X474299Y1544750D03*
X452199Y1550650D03*
X444299Y1532650D03*
X439599Y1552150D03*
X465999Y1603450D03*
X487099Y1606250D03*
X449199Y1579050D03*
X443799Y1612250D03*
X460199Y1632850D03*
X484999Y1636550D03*
X501399Y1634550D03*
X508199Y1610450D03*
X510100Y1579800D03*
X472299Y1572050D03*
X502199Y1566250D03*
X472499Y1620550D03*
Y1611550D03*
X484200Y1579900D03*
X432499Y1617550D03*
X434500Y1579500D03*
X431999Y1605550D03*
X435300Y1715300D03*
X448399Y1699450D03*
X447699Y1682850D03*
X449599Y1656950D03*
X483599Y1662550D03*
X485599Y1694850D03*
X502899Y1709650D03*
X507399Y1683350D03*
X509199Y1660550D03*
X468499Y1712550D03*
X467999Y1687050D03*
Y1696050D03*
Y1668050D03*
X432400Y1680100D03*
X428600Y1691200D03*
X436799Y1772550D03*
X472699Y1792150D03*
X429499Y1748050D03*
X458499Y1742050D03*
X441499Y1758050D03*
X480999Y1756050D03*
X463999Y1772050D03*
X445499Y1792550D03*
X508200Y1758200D03*
X484999Y1779050D03*
X496999Y1799550D03*
X481299Y1811150D03*
X448099Y1809450D03*
X499999Y1854950D03*
X480499Y1855450D03*
X464999D03*
X443999Y1855950D03*
X476199Y1877450D03*
X434299Y1876050D03*
X446999Y1880050D03*
X492999Y1878050D03*
X504799Y1967550D03*
Y1939550D03*
Y1958550D03*
X505799Y1921050D03*
Y1912050D03*
Y1893050D03*
X475199Y1951950D03*
Y1923950D03*
Y1942950D03*
X476199Y1905450D03*
Y1896450D03*
X459299Y1966850D03*
Y1938850D03*
Y1957850D03*
X460299Y1920350D03*
Y1911350D03*
Y1892350D03*
X433299Y1950550D03*
Y1922550D03*
Y1941550D03*
X434299Y1904050D03*
Y1895050D03*
X445999Y1954550D03*
Y1945550D03*
Y1926550D03*
X446999Y1908050D03*
Y1899050D03*
X493499Y1909050D03*
X492499Y1955550D03*
X491999Y1943550D03*
Y1924550D03*
X492999Y1897050D03*
X509299Y1977250D03*
X493799D03*
X473299D03*
X455799Y1976750D03*
X436299Y1977250D03*
X492500Y1987500D03*
X476000Y1987000D03*
X456500Y1987500D03*
X438999Y1987550D03*
X522899Y64350D03*
Y45350D03*
X587999Y63550D03*
X588499Y46550D03*
X587999Y25050D03*
X541499Y63550D03*
X541999Y46550D03*
X541499Y25050D03*
X516499Y6550D03*
X535999D03*
X551499D03*
X570999Y6050D03*
X588499Y6550D03*
X523899Y85350D03*
X520299Y141450D03*
Y122450D03*
X569099Y112550D03*
X568099Y91550D03*
Y72550D03*
X562799Y146750D03*
Y127750D03*
X587999Y145050D03*
X588499Y125550D03*
X541499Y145050D03*
X541999Y125550D03*
Y108050D03*
Y79050D03*
Y93550D03*
X565999Y199950D03*
X528799D03*
X521299Y162450D03*
X563799Y167750D03*
X587999Y217050D03*
X568499Y217550D03*
X552999D03*
X533499D03*
X588999Y185050D03*
X587999Y164050D03*
X542499Y185050D03*
X541499Y164050D03*
X544799Y293950D03*
X540099Y306550D03*
X516899Y306950D03*
X515499Y284050D03*
X536499Y283050D03*
X525999Y255050D03*
X540499D03*
X572999Y287050D03*
X572499Y306550D03*
X572999Y269550D03*
Y255050D03*
X579899Y375750D03*
X530999Y381550D03*
X520499Y353550D03*
X548100Y362200D03*
X573499Y346550D03*
X572499Y325550D03*
X577899Y460550D03*
X578399Y441050D03*
X577399Y420050D03*
X539799Y466050D03*
X538799Y445050D03*
X576099Y481850D03*
X511299Y449150D03*
X519499Y471550D03*
X518999Y416550D03*
X592499Y478050D03*
Y459050D03*
X592999Y439550D03*
Y422050D03*
Y407550D03*
X556499Y467550D03*
X555999Y412550D03*
X539299Y485550D03*
X576599Y522350D03*
X577099Y502850D03*
X579499Y561550D03*
X558499Y562550D03*
X538999Y562050D03*
X535499Y545050D03*
X514499Y546050D03*
X518999Y508550D03*
X519499Y489050D03*
X555999Y504550D03*
X556499Y485050D03*
X534499Y640050D03*
X586299Y711250D03*
X565699Y710650D03*
X549999Y710050D03*
X547999Y728550D03*
X573499Y690550D03*
Y673050D03*
Y658550D03*
X534499Y672050D03*
Y654550D03*
Y805950D03*
X511199Y782050D03*
X527499Y747150D03*
X525499Y772450D03*
X547499Y799050D03*
Y780050D03*
X547999Y760550D03*
Y743050D03*
X575499Y802050D03*
X575999Y782550D03*
Y765050D03*
X577999Y732050D03*
X575999Y750550D03*
X526499Y851150D03*
X510899Y868150D03*
X578299Y895650D03*
X541399Y873450D03*
Y854450D03*
X512899Y842550D03*
Y823550D03*
X521999Y895550D03*
X522499Y876050D03*
X576499Y842050D03*
X575499Y821050D03*
X583299Y961450D03*
X578299Y914650D03*
X540299Y956850D03*
X539299Y935850D03*
X570899Y965850D03*
Y946850D03*
X521999Y914550D03*
X562999Y898050D03*
X560499Y968050D03*
X560999Y948550D03*
Y916550D03*
Y931050D03*
X516499Y957050D03*
X514499Y975550D03*
X583299Y980450D03*
X534599Y1048550D03*
X571899Y986850D03*
X573499Y1055550D03*
Y1036550D03*
X541899Y1021450D03*
X540899Y1000450D03*
Y981450D03*
X560499Y987050D03*
X560999Y999050D03*
X558999Y1049550D03*
Y1017550D03*
Y1032050D03*
X513999Y1046050D03*
Y1027050D03*
X514499Y1007550D03*
Y990050D03*
X588499Y1101550D03*
X578999Y1114550D03*
X568499Y1101550D03*
X564499Y1116050D03*
X548999D03*
X529499D03*
X511999Y1115550D03*
X553999Y1103050D03*
X538499D03*
X518999D03*
X535599Y1069550D03*
X574499Y1076550D03*
X558499Y1088050D03*
Y1069050D03*
X547099Y1202750D03*
Y1221750D03*
X546499Y1180750D03*
Y1195250D03*
X567999Y1215550D03*
Y1206550D03*
Y1187550D03*
X527999Y1212550D03*
X527499Y1200550D03*
Y1181550D03*
X579299Y1300750D03*
X527499Y1278150D03*
X530499Y1297050D03*
X561099Y1301050D03*
X566399Y1273850D03*
X549399Y1302850D03*
Y1274850D03*
Y1293850D03*
X548799Y1252850D03*
Y1267350D03*
X547099Y1230750D03*
X583299Y1283250D03*
Y1255250D03*
Y1274250D03*
X582699Y1233250D03*
Y1247750D03*
X565999Y1248550D03*
Y1234050D03*
X525999Y1263050D03*
Y1245550D03*
Y1231050D03*
X555699Y1322950D03*
X581999Y1370150D03*
X559099Y1343250D03*
X545099Y1355250D03*
X518499Y1346950D03*
X540399Y1382150D03*
X523999Y1391050D03*
X523499Y1360050D03*
Y1379050D03*
X580999Y1412750D03*
X575699Y1438950D03*
X538799Y1409750D03*
X536799Y1436350D03*
X528499Y1460250D03*
X546099Y1467550D03*
X582999Y1461250D03*
X557499Y1443050D03*
Y1452050D03*
Y1424050D03*
X516999Y1437050D03*
X517499Y1449050D03*
X516999Y1418050D03*
X590599Y1483450D03*
X529799Y1555050D03*
X567999Y1549950D03*
X582299Y1534150D03*
X538999Y1528350D03*
X518899Y1530150D03*
X532499Y1635550D03*
X552099Y1601950D03*
X553399Y1624550D03*
X590799Y1627850D03*
X588000Y1604000D03*
X588099Y1572050D03*
X552199Y1576650D03*
X569499Y1619550D03*
Y1610550D03*
X573400Y1577600D03*
X529499Y1616550D03*
X533800Y1575500D03*
X528999Y1604550D03*
X518499Y1643950D03*
X538299Y1721050D03*
X532599Y1655650D03*
X554199Y1651950D03*
X555199Y1674750D03*
X555399Y1689350D03*
X555899Y1706750D03*
X580299Y1722550D03*
X590599Y1694450D03*
X580799Y1646150D03*
X572999Y1694550D03*
Y1703550D03*
Y1675550D03*
X532499Y1688550D03*
X532999Y1700550D03*
X532499Y1669550D03*
X582599Y1740050D03*
X560399Y1792550D03*
X555500Y1802700D03*
X539499Y1788150D03*
X526499Y1801150D03*
X556199Y1727050D03*
X522300Y1739200D03*
X532499Y1763050D03*
X515499Y1779050D03*
X531799Y1818450D03*
X514199Y1815750D03*
X591499Y1855950D03*
X573999Y1855450D03*
X554499Y1855950D03*
X538999D03*
X517499Y1855450D03*
X588899Y1882350D03*
X562599Y1874450D03*
X519399Y1876750D03*
X533499Y1884050D03*
X575999Y1888050D03*
X587899Y1956850D03*
Y1928850D03*
Y1947850D03*
X588899Y1910350D03*
Y1901350D03*
X561599Y1948950D03*
Y1920950D03*
Y1939950D03*
X562599Y1902450D03*
Y1893450D03*
X546999Y1966850D03*
Y1938850D03*
Y1957850D03*
X547999Y1920350D03*
Y1911350D03*
Y1892350D03*
X518399Y1951250D03*
Y1923250D03*
Y1942250D03*
X519399Y1904750D03*
Y1895750D03*
X532499Y1958550D03*
Y1949550D03*
Y1930550D03*
X533499Y1912050D03*
Y1903050D03*
X575999Y1907050D03*
X576499Y1919050D03*
X574999Y1953550D03*
X575499Y1965550D03*
X574999Y1934550D03*
X585799Y1976250D03*
X570299D03*
X546299Y1977250D03*
X528799Y1976750D03*
X568999Y1987050D03*
X553499D03*
X588499Y1986550D03*
X511999Y1987550D03*
X531500Y1987500D03*
X603999Y54350D03*
Y35350D03*
X651799Y59650D03*
Y40650D03*
X674999Y59050D03*
X675499Y42050D03*
X674999Y20550D03*
X624499Y61550D03*
X624999Y44550D03*
X624499Y23050D03*
X608499Y6550D03*
X625999Y7050D03*
X645499D03*
X660999D03*
X604999Y75350D03*
X603999Y133750D03*
X652799Y80650D03*
X649899Y138350D03*
X674999Y140550D03*
X675499Y121050D03*
Y103550D03*
Y74550D03*
Y89050D03*
X624499Y143050D03*
X624999Y123550D03*
X623899Y202550D03*
X604999Y173750D03*
X603999Y152750D03*
X650899Y178350D03*
X649899Y157350D03*
X662499Y218050D03*
X642999D03*
X625499Y217550D03*
X605499D03*
X675999Y180550D03*
X674999Y159550D03*
X625499Y183050D03*
X624499Y162050D03*
X656499Y307050D03*
X653999Y286550D03*
X627999Y280050D03*
X627499Y299550D03*
X627999Y262550D03*
Y248050D03*
X599799Y385150D03*
X600299Y365650D03*
X599299Y344650D03*
X659899Y363250D03*
X632399Y358750D03*
X635399Y376250D03*
X607399Y380250D03*
X643599Y395950D03*
X655999Y344050D03*
X656499Y324550D03*
X628499Y339550D03*
X628200Y320000D03*
X644099Y450950D03*
X644599Y416950D03*
X644099Y436450D03*
X621499Y466550D03*
X621999Y432550D03*
X621499Y452050D03*
X620999Y411550D03*
X666999Y476550D03*
X643499Y546750D03*
X642499Y525750D03*
X613700Y504600D03*
X621499Y484050D03*
X593499Y499050D03*
X666499Y547050D03*
X666999Y508550D03*
X666499Y528050D03*
X666999Y491050D03*
X642999Y566250D03*
X640599Y604650D03*
X673999Y645150D03*
X645099Y639150D03*
X631999Y639650D03*
X665999Y623550D03*
X620499D03*
Y609050D03*
X595999Y641550D03*
Y624050D03*
Y609550D03*
X674999Y601550D03*
X646999Y584550D03*
X625999Y585050D03*
X606499Y584550D03*
X667499Y568050D03*
X651999Y718350D03*
X648999Y702350D03*
X629099Y714050D03*
X605299Y661750D03*
X609499Y708050D03*
X607499Y726550D03*
X647499Y689050D03*
Y671550D03*
Y657050D03*
X622999Y689550D03*
Y672050D03*
X597999Y690050D03*
X647399Y742150D03*
X653099Y803350D03*
X621499Y767150D03*
X633499Y750150D03*
X606999Y797050D03*
Y778050D03*
X607499Y758550D03*
Y741050D03*
X664999Y805050D03*
Y786050D03*
X665499Y766550D03*
X645799Y816650D03*
X642599Y883250D03*
X641599Y862250D03*
Y843250D03*
X621999Y835050D03*
X612999Y854550D03*
X629499Y853050D03*
Y868550D03*
X613499Y868050D03*
X663499Y896050D03*
X663999Y876550D03*
Y844550D03*
Y859050D03*
X665999Y826050D03*
X639499Y971150D03*
Y952150D03*
X616699Y967250D03*
Y948250D03*
X658999Y959050D03*
X656999Y977550D03*
X603499Y904050D03*
X601499Y954550D03*
Y922550D03*
Y937050D03*
X664499Y936050D03*
X663499Y915050D03*
X673999Y1036550D03*
Y1017550D03*
X674699Y1061450D03*
X611399Y1045650D03*
Y1026650D03*
X617699Y988250D03*
X656499Y1048050D03*
Y1029050D03*
X656999Y1009550D03*
Y992050D03*
X631999Y1001550D03*
X629999Y1052050D03*
Y1020050D03*
Y1034550D03*
X600999Y1002050D03*
X598999Y1052550D03*
Y1020550D03*
Y1035050D03*
X633999Y1103050D03*
X669499Y1116550D03*
X616499Y1115050D03*
X605999Y1102050D03*
X598999Y1114550D03*
X674699Y1080450D03*
X674999Y1134950D03*
X641799Y1137650D03*
X627699Y1143550D03*
X612399Y1066650D03*
X629499Y1090550D03*
Y1071550D03*
X598499Y1091050D03*
Y1072050D03*
X603899Y1157850D03*
X626199Y1183450D03*
X597599Y1196050D03*
X596599Y1215050D03*
X651599Y1203050D03*
X650599Y1182050D03*
X651299Y1174150D03*
X650299Y1153150D03*
X668199Y1173850D03*
X667199Y1152850D03*
X671199Y1213750D03*
X670199Y1192750D03*
X628699Y1164550D03*
X668699Y1227650D03*
X672999Y1303450D03*
X608899Y1305050D03*
X600899Y1238650D03*
X630499Y1243950D03*
X657099Y1272850D03*
X657799Y1288450D03*
X656399Y1307050D03*
X618199Y1296250D03*
Y1268250D03*
Y1287250D03*
X617599Y1246250D03*
Y1260750D03*
X638999Y1286550D03*
Y1295550D03*
Y1267550D03*
X598499Y1280550D03*
X598999Y1292550D03*
X598499Y1261550D03*
X671999Y1324950D03*
X631799Y1322650D03*
X605599Y1326350D03*
X665699Y1337250D03*
X606199Y1338250D03*
X617899Y1360850D03*
X625499Y1383450D03*
X632499Y1347950D03*
X599999Y1382550D03*
X599499Y1351550D03*
Y1370550D03*
X654999Y1385050D03*
X654499Y1373050D03*
Y1354050D03*
X659699Y1445950D03*
X604899Y1407750D03*
X601299Y1447650D03*
X636799Y1461250D03*
X626799Y1432350D03*
X627499Y1406050D03*
X665699Y1462250D03*
X652999Y1435550D03*
Y1418050D03*
Y1403550D03*
X656099Y1479550D03*
X625199Y1489150D03*
X610899Y1496750D03*
X672399Y1508750D03*
X673699Y1535350D03*
X662099Y1549650D03*
X643099Y1541350D03*
X599799Y1544650D03*
X617699Y1530350D03*
X670699Y1603150D03*
X671399Y1625350D03*
X628499Y1636650D03*
X633499Y1615450D03*
X635500Y1603900D03*
X652399Y1575850D03*
X623499Y1564050D03*
X652499Y1618550D03*
Y1609550D03*
X639200Y1576200D03*
X612499Y1615550D03*
X611900Y1577900D03*
X611999Y1603550D03*
X649399Y1644950D03*
X657099Y1668850D03*
X635099Y1691150D03*
X607599Y1716450D03*
X593399Y1668850D03*
X627299Y1659550D03*
X600599Y1645450D03*
X674999Y1676550D03*
X656499Y1697050D03*
X609499Y1692050D03*
Y1675050D03*
X642499Y1709050D03*
X665399Y1752350D03*
X650399Y1771250D03*
X593299Y1760950D03*
X619499Y1803150D03*
X627273Y1793905D03*
X606999Y1745550D03*
X625499Y1725050D03*
X675499Y1757050D03*
X675999Y1769050D03*
X675499Y1738050D03*
X642400Y1800100D03*
X659159Y1792278D03*
X626999Y1800050D03*
X645099Y1877550D03*
X667999Y1870950D03*
X632799Y1820450D03*
X627494Y1829068D03*
X608599Y1810750D03*
X669399Y1855350D03*
X627499Y1855950D03*
X611999D03*
X630699Y1872750D03*
X602799Y1887350D03*
X640999Y1815550D03*
X595199Y1820910D03*
X659549Y1815384D03*
X644049Y1810834D03*
X633837Y1807384D03*
X646799Y1926450D03*
X645399Y1906150D03*
X673899Y1966850D03*
Y1938850D03*
Y1957850D03*
X674899Y1920350D03*
Y1911350D03*
Y1892350D03*
X660299Y1964550D03*
Y1936550D03*
Y1955550D03*
X661299Y1918050D03*
Y1909050D03*
Y1890050D03*
X629699Y1947250D03*
Y1919250D03*
Y1938250D03*
X630699Y1900750D03*
Y1891750D03*
X601799Y1961850D03*
Y1933850D03*
Y1952850D03*
X602799Y1915350D03*
Y1906350D03*
X616499Y1913050D03*
Y1922050D03*
Y1894050D03*
X615499Y1959550D03*
Y1968550D03*
Y1940550D03*
X644999Y1953050D03*
X645499Y1965050D03*
X644999Y1934050D03*
X659299Y1976250D03*
X643799D03*
X622799D03*
X605299Y1975750D03*
X642499Y1987050D03*
X626999D03*
X661999Y1986550D03*
X605999Y1987050D03*
X751499Y48350D03*
X694999Y62650D03*
X757499Y63050D03*
Y44050D03*
X725499Y62050D03*
X725999Y45050D03*
X725499Y23550D03*
X680499Y6550D03*
X697999Y7050D03*
X712499Y6050D03*
X729999Y6550D03*
X749499D03*
X752099Y112150D03*
X738199Y137450D03*
X695999Y102650D03*
X694999Y81650D03*
X699699Y141750D03*
X758499Y84050D03*
X725499Y143550D03*
X725999Y124050D03*
Y106550D03*
Y77550D03*
Y92050D03*
X728899Y204550D03*
X688999Y196550D03*
X700699Y181750D03*
X699699Y160750D03*
X749499Y218550D03*
X729499D03*
X711999Y218050D03*
X677999D03*
X726499Y183550D03*
X725499Y162550D03*
X711999Y307550D03*
Y293050D03*
X723200Y275500D03*
X711499Y252550D03*
X680500Y280700D03*
X682999Y300050D03*
X683499Y263050D03*
Y248550D03*
X749899Y398550D03*
X711499Y344550D03*
X711999Y325050D03*
X683999Y340050D03*
X682999Y319050D03*
X713699Y455450D03*
X713199Y474950D03*
X712699Y434450D03*
X750399Y453550D03*
X750899Y419550D03*
X750399Y439050D03*
X694999Y480550D03*
X737999Y467050D03*
X691399Y548350D03*
X755699Y528650D03*
X756199Y509150D03*
X755199Y488150D03*
X754499Y564650D03*
X713099Y561550D03*
X713599Y542050D03*
X712599Y521050D03*
X713199Y489450D03*
X695499Y521050D03*
X695999Y501550D03*
X737999Y559050D03*
X738499Y539550D03*
Y522050D03*
Y507550D03*
X738999Y488050D03*
X691899Y588850D03*
X692399Y569350D03*
X754999Y605150D03*
X755499Y585650D03*
X717099Y636050D03*
X729699Y640350D03*
X731499Y604050D03*
Y586550D03*
Y572050D03*
X690499Y623050D03*
X744999Y626550D03*
X721499Y617550D03*
X699999Y610050D03*
X757400Y686300D03*
X720899Y712250D03*
X732499Y729250D03*
X681899Y713650D03*
X679299Y703050D03*
X727099Y715050D03*
X739399Y688150D03*
X747999Y670750D03*
X723499Y654850D03*
X693999Y648150D03*
X754999Y694050D03*
X702999Y688050D03*
Y670550D03*
Y656050D03*
X678499Y688550D03*
Y671050D03*
X749999Y700050D03*
X710899Y751150D03*
X696299Y741850D03*
X685999Y780050D03*
X694599Y763450D03*
X743099Y785350D03*
X733799Y761450D03*
X716599Y736850D03*
X723999Y802350D03*
Y783350D03*
X687099Y804650D03*
X706999Y811550D03*
Y792550D03*
X707499Y773050D03*
X728499Y841850D03*
X724999Y823350D03*
X688099Y844650D03*
X687099Y823650D03*
X729999Y881850D03*
Y862850D03*
X751599Y887350D03*
X705999Y851050D03*
Y865550D03*
X707999Y832550D03*
X751499Y855550D03*
Y836550D03*
X751999Y817050D03*
X707399Y918550D03*
Y899550D03*
X678299Y978350D03*
X730999Y902850D03*
X688099Y936350D03*
X687099Y915350D03*
Y896350D03*
X724699Y976250D03*
X723699Y955250D03*
Y936250D03*
X752599Y927350D03*
X751599Y906350D03*
X706499Y942550D03*
X749999Y965550D03*
Y946550D03*
X751399Y1023550D03*
Y1004550D03*
X752399Y1052550D03*
X734999Y1030550D03*
Y1045050D03*
X713999Y1049050D03*
Y1031550D03*
Y1017050D03*
X678299Y997350D03*
X694999Y993050D03*
X692999Y1043550D03*
Y1011550D03*
Y1026050D03*
X750999Y986550D03*
X734999Y1062550D03*
X713499Y1068550D03*
X737999Y1119050D03*
X727499Y1106050D03*
X720499Y1118550D03*
X709999Y1105550D03*
X700499Y1118550D03*
X689999Y1105550D03*
X727499Y1132650D03*
X704299D03*
X692499Y1082050D03*
Y1063050D03*
X753999Y1100050D03*
X713599Y1214650D03*
X756799Y1217650D03*
X758799Y1190150D03*
Y1199150D03*
X717999Y1169150D03*
X716999Y1148150D03*
X714399Y1199750D03*
X713399Y1178750D03*
X735999Y1220550D03*
Y1206050D03*
X737999Y1187550D03*
Y1178550D03*
Y1159550D03*
X695999Y1217550D03*
Y1203050D03*
X697999Y1184550D03*
X697499Y1172550D03*
Y1153550D03*
X684299Y1249550D03*
X740799Y1298750D03*
X723499Y1292650D03*
Y1278150D03*
X725499Y1250650D03*
Y1259650D03*
Y1231650D03*
X755399Y1300650D03*
Y1286150D03*
X757399Y1258650D03*
Y1267650D03*
Y1239650D03*
X756799Y1232150D03*
X709699Y1264550D03*
X708699Y1243550D03*
X740499Y1252550D03*
Y1270050D03*
X695999Y1235050D03*
X739199Y1348950D03*
X742099Y1320650D03*
X719199Y1322350D03*
X695999Y1323350D03*
X677999Y1347550D03*
X680299Y1365850D03*
X713899Y1386450D03*
X707899Y1346250D03*
X734199Y1373850D03*
X694999Y1388050D03*
Y1379050D03*
Y1360050D03*
X702299Y1404450D03*
X736199Y1399050D03*
X741099Y1450250D03*
X737799Y1428350D03*
X716899Y1459850D03*
X700899Y1450250D03*
X681299Y1393150D03*
X678299Y1425050D03*
X686999Y1468850D03*
X719499Y1446650D03*
X721899Y1419050D03*
X754999Y1420050D03*
Y1437550D03*
X692999Y1421050D03*
Y1406550D03*
X741099Y1498150D03*
X729199Y1492750D03*
X716199Y1503050D03*
X735799Y1533650D03*
X714599Y1533950D03*
X708899Y1549250D03*
X685299Y1551950D03*
X747199Y1509150D03*
X755499Y1507550D03*
X734499Y1563550D03*
X722199Y1564250D03*
X706700Y1579900D03*
X698599Y1568550D03*
X681299Y1579150D03*
X693599Y1602450D03*
X686699Y1638650D03*
X742000Y1560000D03*
X743400Y1578700D03*
X719999Y1605050D03*
X751300Y1604900D03*
X732999Y1620050D03*
X756299Y1679050D03*
X738799Y1677250D03*
X750099Y1694950D03*
X756499Y1712150D03*
X739199Y1716750D03*
X721199Y1723750D03*
X727399Y1694350D03*
X717099Y1702450D03*
X693099Y1722350D03*
X691999Y1660550D03*
X751899Y1752150D03*
X747799Y1766750D03*
X729499Y1778750D03*
X729999Y1756450D03*
X747499Y1734350D03*
X702599Y1730550D03*
X709099Y1751850D03*
X690499Y1744950D03*
X694599Y1768450D03*
X715999Y1763050D03*
Y1772050D03*
Y1744050D03*
X693549Y1793134D03*
X706549Y1793634D03*
X744049Y1791634D03*
X740549Y1802634D03*
X753949Y1798194D03*
X705000Y1811900D03*
X686999Y1870250D03*
X728099Y1844750D03*
X747599Y1844250D03*
X743799Y1888850D03*
X728299D03*
X753699Y1879250D03*
X732199Y1878750D03*
X744699Y1868450D03*
X758399Y1868350D03*
X723199Y1867950D03*
X743399Y1855850D03*
X725899Y1855350D03*
X690899Y1855850D03*
X706399D03*
X697999Y1844550D03*
X732999Y1868550D03*
X711500Y1817700D03*
X704300Y1828400D03*
X686473Y1818375D03*
X740549Y1810384D03*
X696299Y1898850D03*
X716599Y1918450D03*
X728799Y1933050D03*
X709199Y1962950D03*
X698299Y1948050D03*
X676399Y1901150D03*
X695299Y1926450D03*
X711899Y1944050D03*
X736799Y1919450D03*
X728799Y1908150D03*
X705599Y1891850D03*
X730499Y1954650D03*
X755299Y1902150D03*
X739799D03*
X685499Y1959050D03*
Y1968050D03*
Y1940050D03*
X755500Y1914500D03*
X721499Y1974550D03*
X696299Y1976250D03*
X678799Y1975750D03*
X754999Y1987550D03*
X737499Y1987050D03*
X717999Y1987550D03*
X702499D03*
X679499Y1987050D03*
X774399Y54050D03*
X763399Y24150D03*
X817599Y43750D03*
X824899Y25150D03*
X813299Y68350D03*
Y49350D03*
X796999Y65550D03*
X797499Y48550D03*
X796999Y27050D03*
X764999Y6550D03*
X784499Y6050D03*
X801999Y6550D03*
X818999Y6050D03*
X836499Y6550D03*
X778399Y105250D03*
X775399Y80250D03*
X821199Y137450D03*
X813299Y110850D03*
X805899Y126150D03*
X767399Y140150D03*
X796599Y123450D03*
X814299Y89350D03*
X796999Y147050D03*
X797499Y127550D03*
Y110050D03*
Y81050D03*
Y95550D03*
X837499Y138550D03*
X838499Y145050D03*
X760799Y181950D03*
X779399Y200550D03*
X786499Y219050D03*
X800999Y216550D03*
X766999Y219050D03*
X797999Y187050D03*
X796999Y166050D03*
X838999Y313550D03*
X821499Y314050D03*
X839299Y390950D03*
X819299Y394250D03*
X838499Y352050D03*
X840299Y430950D03*
X839299Y409950D03*
X820299Y434250D03*
X819299Y413250D03*
X802999Y466050D03*
X774999Y476550D03*
Y462050D03*
X825399Y540950D03*
X825899Y521450D03*
X824899Y500450D03*
X835599Y564050D03*
X834599Y543050D03*
X802999Y558050D03*
X803499Y538550D03*
Y521050D03*
Y506550D03*
X803999Y487050D03*
X775499Y553550D03*
X774499Y532550D03*
X774999Y494050D03*
X774499Y513550D03*
X835099Y583550D03*
X814499Y601550D03*
Y584050D03*
Y569550D03*
X789999Y602050D03*
Y584550D03*
Y570050D03*
X785499Y641050D03*
X777499Y638050D03*
X771800Y686600D03*
X786500Y686100D03*
X798000Y686400D03*
X764599Y655750D03*
X777499Y664550D03*
X794999D03*
X806300Y670600D03*
X841000Y671100D03*
X766499Y699050D03*
X782999Y699550D03*
X836149Y714050D03*
X766499Y705550D03*
X778999Y806950D03*
X763099Y796350D03*
X835999Y799050D03*
Y781550D03*
Y767050D03*
X811499Y799550D03*
Y782050D03*
Y767550D03*
X837799Y754150D03*
X825199Y850850D03*
X827699Y892450D03*
Y873450D03*
X776199Y879250D03*
X775199Y858250D03*
Y839250D03*
X800999Y892550D03*
X802999Y874050D03*
X801999Y853050D03*
Y834050D03*
X802499Y814550D03*
X828699Y913450D03*
X826999Y963150D03*
X773199Y960650D03*
X772199Y939650D03*
Y920650D03*
X800499Y944050D03*
Y963050D03*
X800999Y924550D03*
Y907050D03*
Y1037550D03*
Y1005550D03*
Y1020050D03*
X827999Y1003150D03*
X826999Y982150D03*
X777899Y1028050D03*
X776899Y1007050D03*
Y988050D03*
X801499Y984050D03*
X783999Y1096550D03*
X760999Y1095550D03*
X789499Y1099550D03*
X773499Y1101050D03*
X769499D03*
X773499Y1105050D03*
X769499D03*
X836149Y1118550D03*
X808299Y1175850D03*
X806599Y1189750D03*
X803599Y1211050D03*
X831499Y1209550D03*
Y1200550D03*
Y1181550D03*
X789499Y1225050D03*
X791499Y1206550D03*
X790999Y1194550D03*
Y1175550D03*
X839999Y1157550D03*
X826199Y1294450D03*
X828199Y1267850D03*
X788999Y1278150D03*
X791999Y1294450D03*
X808199Y1290350D03*
Y1275850D03*
X810199Y1248350D03*
Y1257350D03*
Y1229350D03*
X829499Y1242550D03*
Y1228050D03*
X789499Y1257050D03*
Y1239550D03*
X825500Y1379000D03*
X831499Y1324950D03*
X795299Y1326650D03*
X822199Y1335250D03*
X819199Y1353550D03*
X798299Y1344250D03*
X779399Y1361850D03*
X762499Y1335550D03*
Y1353050D03*
X799999Y1340550D03*
Y1358050D03*
X806499Y1390550D03*
X803299Y1426650D03*
X773999Y1393450D03*
X763399Y1401450D03*
X781999Y1434650D03*
X805899Y1464250D03*
X771399Y1474550D03*
X806499Y1408050D03*
X834499Y1397550D03*
X836600Y1416500D03*
X769300Y1488100D03*
X779000Y1488400D03*
X786500Y1488600D03*
X801300Y1489000D03*
X770999Y1500050D03*
X780499D03*
X839499Y1523550D03*
X773499Y1509050D03*
X769499D03*
X786999Y1506550D03*
X813300Y1604100D03*
X827199Y1622750D03*
X841499Y1638950D03*
X803599Y1618350D03*
X826499Y1609050D03*
X825999Y1578050D03*
X839899Y1562050D03*
X829200Y1719800D03*
X824100Y1719900D03*
X819400Y1721900D03*
X837199Y1660550D03*
X814599Y1642650D03*
X776999Y1647650D03*
X797299Y1646650D03*
X802899Y1670550D03*
X839199Y1683550D03*
X808899Y1698450D03*
X779999Y1717050D03*
X770399Y1699650D03*
X765099Y1664950D03*
X823499Y1693050D03*
Y1702050D03*
Y1674050D03*
X782999Y1687050D03*
X783499Y1699050D03*
X782999Y1668050D03*
X819200Y1727100D03*
X808299Y1755250D03*
X794499Y1734550D03*
X770099Y1730350D03*
X779899Y1748150D03*
X787900Y1758800D03*
X765600Y1756800D03*
X827999Y1791550D03*
X767159Y1792364D03*
X829799Y1856350D03*
X809299D03*
X791799Y1855850D03*
X801099Y1844750D03*
X785599D03*
X765099D03*
X780799Y1888850D03*
X763299Y1888350D03*
X833100Y1878500D03*
X806199Y1879250D03*
X788699Y1878750D03*
X769199Y1879250D03*
X833199Y1868450D03*
X818900Y1870800D03*
X797199Y1868450D03*
X779699Y1867950D03*
X779399Y1855850D03*
X763899D03*
X783499Y1907050D03*
X774499Y1908050D03*
X765999D03*
X838999Y1928550D03*
X790499Y1913050D03*
X775999Y1916050D03*
X840999Y1970550D03*
X768499Y1917550D03*
X813599Y1979950D03*
X789299Y1983850D03*
X829499Y1980250D03*
X829999Y1987550D03*
X812499Y1987050D03*
X792999Y1987550D03*
X777499D03*
X844799Y19850D03*
X860799Y24150D03*
X885999Y21150D03*
X855999Y6550D03*
X871499D03*
X890999Y6050D03*
X908499Y6550D03*
X923999Y6050D03*
X890700Y132500D03*
X872100Y132700D03*
X854300Y132600D03*
X891999Y146050D03*
X906999Y224150D03*
X887400Y233555D03*
X871786Y233924D03*
Y218924D03*
Y203924D03*
X907999Y264150D03*
X906999Y243150D03*
X906399Y314250D03*
Y295250D03*
X863999Y313550D03*
X887400Y259700D03*
X879878Y247724D03*
X907399Y335250D03*
X875799Y386250D03*
X904999Y385050D03*
Y370550D03*
X854499Y387550D03*
Y373050D03*
X858400Y352300D03*
X847999Y352550D03*
X870600Y346700D03*
X876799Y426250D03*
X875799Y405250D03*
X884399Y462450D03*
Y443450D03*
X905499Y462050D03*
X904499Y441050D03*
Y422050D03*
X904999Y402550D03*
X854999Y464550D03*
X853999Y443550D03*
X854499Y405050D03*
X853999Y424550D03*
X861199Y546050D03*
X860199Y525050D03*
X885399Y483450D03*
X914699Y524650D03*
X913699Y503650D03*
Y484650D03*
X860699Y565550D03*
X898999Y622050D03*
Y604550D03*
X860499Y607550D03*
X861800Y591200D03*
X918999Y641550D03*
X870719Y609705D03*
X894000Y642400D03*
X870719Y639705D03*
X870773Y624705D03*
X895999Y720050D03*
Y702550D03*
X900999Y670050D03*
Y652550D03*
X918499Y712050D03*
X918999Y673550D03*
X918499Y693050D03*
X918999Y656050D03*
X887401Y665000D03*
X881200Y652100D03*
X859999Y713050D03*
X871385Y719436D03*
X871786Y709482D03*
X871499Y689436D03*
X871786Y679436D03*
X860796Y678632D03*
X921399Y796350D03*
X921899Y776850D03*
Y759350D03*
Y744850D03*
X884499Y799050D03*
Y781550D03*
Y767050D03*
X859999Y799550D03*
Y782050D03*
Y767550D03*
X919499Y733050D03*
X856299Y753150D03*
X846799Y754150D03*
X865000Y752100D03*
X889699Y876050D03*
X847799Y828250D03*
X857099Y873450D03*
X920399Y886850D03*
Y869350D03*
Y854850D03*
X922399Y836350D03*
X921399Y815350D03*
X898499Y862050D03*
Y844550D03*
Y830050D03*
X873999Y862550D03*
Y845050D03*
Y830550D03*
X886999Y947250D03*
Y907350D03*
X867199Y941350D03*
X866199Y920350D03*
Y901350D03*
X850999Y962550D03*
Y943550D03*
X919899Y925350D03*
X920899Y946350D03*
X919899Y906350D03*
X851999Y983550D03*
X921499Y1031050D03*
X920999Y1050550D03*
X921499Y1013550D03*
Y999050D03*
X870468Y1030227D03*
X880033Y1058592D03*
X886919Y1044478D03*
X870298Y1045227D03*
X870777Y1014948D03*
X921999Y1090550D03*
X920999Y1069550D03*
X887400Y1070600D03*
X859999Y1118550D03*
X841999D03*
X845799Y1190450D03*
X849799Y1199750D03*
X846499Y1170450D03*
X897299Y1182450D03*
X887999Y1209350D03*
X871399Y1201850D03*
Y1210850D03*
Y1182850D03*
X892499Y1224550D03*
X851999Y1218550D03*
X856400Y1157700D03*
X848999Y1158050D03*
X863300Y1153800D03*
X872099Y1268150D03*
X871399Y1291450D03*
X860099Y1295450D03*
X869399Y1243850D03*
Y1229350D03*
X890499Y1285550D03*
Y1271050D03*
X892499Y1252550D03*
Y1243550D03*
X850499Y1300050D03*
Y1282550D03*
Y1268050D03*
X852499Y1249550D03*
X851999Y1237550D03*
X875399Y1322650D03*
X868499Y1392550D03*
X890999Y1336550D03*
Y1354050D03*
X841999Y1341050D03*
Y1358550D03*
X894499Y1423550D03*
Y1441050D03*
X868499Y1410050D03*
X886913Y1449010D03*
X879727Y1463696D03*
X871836Y1450460D03*
Y1435460D03*
Y1420460D03*
X914599Y1521650D03*
X910899Y1549250D03*
X894499Y1522050D03*
Y1539550D03*
X895499Y1488050D03*
X902759Y1509585D03*
X861999Y1522550D03*
X843999Y1523550D03*
X887499Y1476050D03*
X865300Y1557700D03*
X923599Y1634350D03*
X909700Y1576400D03*
X907500Y1604000D03*
X908899Y1630050D03*
X868099Y1635650D03*
X887299Y1620050D03*
X886900Y1604100D03*
X873099Y1572550D03*
X850099Y1572250D03*
X849900Y1605100D03*
X852499Y1621350D03*
X866499Y1603050D03*
Y1612050D03*
X864000Y1578200D03*
X858400Y1561900D03*
X850499Y1562050D03*
X879200Y1698700D03*
X879900Y1709300D03*
X883900Y1709500D03*
X855350Y1703201D03*
X914899Y1657550D03*
X922599Y1682150D03*
X903599Y1686850D03*
X895999Y1661250D03*
X877699Y1646650D03*
X855799Y1658250D03*
X882999Y1678250D03*
X864099Y1683550D03*
X842799Y1701150D03*
X875900Y1709500D03*
X902900Y1709800D03*
X842500Y1799000D03*
X892700Y1727800D03*
X879399Y1798150D03*
X911299Y1800850D03*
X864000Y1748000D03*
X866699Y1770950D03*
X853799Y1790850D03*
X844499Y1788050D03*
X892700Y1736500D03*
X863099Y1813150D03*
X903299Y1814750D03*
X894999Y1829050D03*
X922899Y1853650D03*
X905299Y1852650D03*
X900299Y1876950D03*
X842199Y1879250D03*
X914999Y1887050D03*
Y1868050D03*
X862499Y1823550D03*
X854977Y1818994D03*
X887401Y1881500D03*
X894000Y1868452D03*
X887499Y1855550D03*
X869999Y1855972D03*
X871836Y1840972D03*
X869634Y1826876D03*
X914899Y1912450D03*
X916599Y1942650D03*
X897599Y1938750D03*
X914899Y1972250D03*
X873399Y1963650D03*
X904299Y1954950D03*
X897299Y1904150D03*
X907599Y1930050D03*
X915499Y1899050D03*
X861414Y1928550D03*
X843999D03*
X856999Y1970050D03*
X849999Y1970550D03*
X865200Y1968000D03*
X879399Y1974550D03*
X850499Y1977950D03*
X868699Y1983250D03*
X921499Y1986550D03*
X901999Y1987050D03*
X864999D03*
X849499D03*
X884499Y1986550D03*
X974699Y64650D03*
X977399Y44050D03*
X954799Y17850D03*
X974699Y21450D03*
X991399Y22450D03*
X1002699Y40050D03*
X991999Y56050D03*
X941499Y6550D03*
X960999D03*
X976499D03*
X995999Y6050D03*
X967499Y47050D03*
Y56050D03*
Y64050D03*
X983099Y83650D03*
X1005299Y71350D03*
X977699Y109150D03*
X994399Y101250D03*
X981099Y123450D03*
X939199Y142050D03*
X968399Y137150D03*
X967999Y73050D03*
Y82050D03*
X988699Y174350D03*
X967399Y180350D03*
X956099Y181350D03*
X958799Y167350D03*
X1004799Y231450D03*
X1005299Y211950D03*
Y194450D03*
Y179950D03*
X952799Y231150D03*
Y213650D03*
Y199150D03*
X982999Y203550D03*
Y221050D03*
Y189050D03*
X932499Y223550D03*
Y206050D03*
Y191550D03*
X1005299Y305450D03*
Y290950D03*
X1005799Y271450D03*
X1004799Y250450D03*
X952799Y310150D03*
X953299Y290650D03*
X952299Y269650D03*
Y250650D03*
X983999Y316050D03*
Y301550D03*
X933499Y304050D03*
X983499Y280550D03*
X982499Y259550D03*
Y240550D03*
X932999Y283050D03*
X931999Y262050D03*
Y243050D03*
X1005799Y382450D03*
X1004799Y361450D03*
X1005299Y322950D03*
X1004799Y342450D03*
X952299Y380650D03*
X952799Y342150D03*
X952299Y361650D03*
X952799Y324650D03*
X984499Y393050D03*
X983499Y372050D03*
Y353050D03*
X983999Y333550D03*
X933999Y395550D03*
X932999Y374550D03*
X933499Y336050D03*
X932999Y355550D03*
X933499Y318550D03*
X966199Y473350D03*
X1000699Y482350D03*
Y463350D03*
X954799Y451650D03*
Y434150D03*
Y419650D03*
X953299Y401650D03*
X983499Y464050D03*
X983999Y427050D03*
Y444550D03*
Y412550D03*
X933499Y447050D03*
X932999Y466550D03*
X933499Y429550D03*
Y415050D03*
X967199Y513350D03*
X966199Y492350D03*
X1001699Y503350D03*
X1003499Y546350D03*
X1003999Y526850D03*
X951299Y560150D03*
Y541150D03*
X951799Y521650D03*
Y504150D03*
Y489650D03*
X985999Y536550D03*
Y554050D03*
Y522050D03*
X935499Y556550D03*
Y539050D03*
Y524550D03*
X984499Y504050D03*
X983499Y483050D03*
X933999Y506550D03*
X932999Y485550D03*
X967799Y606350D03*
X966799Y585350D03*
Y566350D03*
X1005999Y636350D03*
Y618850D03*
X1004499Y586350D03*
X1005999Y604350D03*
X1003499Y565350D03*
X950299Y631650D03*
Y614150D03*
Y599650D03*
X952299Y581150D03*
X969499Y639050D03*
X986499Y613550D03*
X985499Y592550D03*
Y573550D03*
X935999Y616050D03*
X934999Y595050D03*
Y576050D03*
X949799Y670150D03*
X950799Y691150D03*
X949799Y651150D03*
X969999Y730550D03*
X968999Y709550D03*
Y690550D03*
X969499Y653550D03*
Y671050D03*
Y795750D03*
X969999Y776250D03*
Y758750D03*
Y744250D03*
X994499Y803550D03*
Y784550D03*
X994999Y747550D03*
Y765050D03*
Y733050D03*
X943999Y806050D03*
X944499Y767550D03*
X943999Y787050D03*
X944499Y750050D03*
Y735550D03*
X970499Y879750D03*
Y862250D03*
Y847750D03*
Y835750D03*
X969499Y814750D03*
X992999Y894550D03*
X993499Y857550D03*
Y875050D03*
Y843050D03*
X942999Y877550D03*
Y860050D03*
Y845550D03*
X995499Y824550D03*
X944999Y827050D03*
X994499Y973550D03*
Y956050D03*
Y941550D03*
X949299Y977450D03*
X970999Y939250D03*
X969999Y918250D03*
Y899250D03*
X993999Y934550D03*
X992999Y913550D03*
X943499Y937050D03*
X942499Y916050D03*
Y897050D03*
X994999Y1033050D03*
Y1045050D03*
X993999Y1012050D03*
Y993050D03*
X948799Y1047950D03*
Y1028950D03*
X949299Y1009450D03*
Y991950D03*
X971499Y1048050D03*
X971999Y1011050D03*
Y1028550D03*
Y996550D03*
X949799Y1068950D03*
Y1080950D03*
X998599Y1128450D03*
Y1110950D03*
Y1096450D03*
X950699Y1139750D03*
Y1122250D03*
Y1107750D03*
X975999Y1115550D03*
Y1133050D03*
Y1101050D03*
X925499Y1135550D03*
Y1118050D03*
Y1103550D03*
X972499Y1088050D03*
X971499Y1067050D03*
X999099Y1214450D03*
Y1199950D03*
Y1187950D03*
X998099Y1147950D03*
Y1166950D03*
X951199Y1225750D03*
Y1211250D03*
Y1199250D03*
X950199Y1159250D03*
Y1178250D03*
X976499Y1219050D03*
Y1204550D03*
X925999Y1221550D03*
Y1207050D03*
X976499Y1192550D03*
X975499Y1171550D03*
Y1152550D03*
X925999Y1195050D03*
X924999Y1174050D03*
Y1155050D03*
X999599Y1291450D03*
X998599Y1270450D03*
Y1251450D03*
X999099Y1231950D03*
X951699Y1302750D03*
X950699Y1281750D03*
Y1262750D03*
X951199Y1243250D03*
X976999Y1296050D03*
X975999Y1275050D03*
Y1256050D03*
X976499Y1236550D03*
X926499Y1298550D03*
X925499Y1277550D03*
X925999Y1239050D03*
X925499Y1258550D03*
X975100Y1342600D03*
X1000700Y1358100D03*
X996500Y1324800D03*
X952499Y1361850D03*
X944000Y1391900D03*
X943799Y1380850D03*
Y1342950D03*
X965099Y1324350D03*
X928499Y1325350D03*
X976499Y1377050D03*
Y1362550D03*
X925999Y1379550D03*
Y1365050D03*
X992500Y1397300D03*
X964400Y1409700D03*
X946700Y1426500D03*
X994200Y1421500D03*
X924999Y1471050D03*
X926499Y1456550D03*
X925499Y1435550D03*
X925999Y1397050D03*
X925499Y1416550D03*
X973200Y1516400D03*
X972500Y1529100D03*
X966600D03*
X961400Y1528700D03*
X961900Y1522400D03*
X967100Y1522800D03*
X973000D03*
X962100Y1516000D03*
X967300Y1516400D03*
X972700Y1534800D03*
X972000Y1547500D03*
X966100D03*
X960900Y1547100D03*
X961400Y1540800D03*
X966600Y1541200D03*
X972500D03*
X961600Y1534400D03*
X966800Y1534800D03*
X972700Y1553300D03*
X961600Y1552900D03*
X966800Y1553300D03*
X944000Y1511300D03*
X943199Y1531650D03*
X924499Y1541550D03*
X924999Y1503050D03*
X924499Y1522550D03*
X924999Y1485550D03*
X972000Y1566000D03*
X966100D03*
X960900Y1565600D03*
X961400Y1559300D03*
X966600Y1559700D03*
X972500D03*
X973000Y1572800D03*
X972300Y1585500D03*
X966400D03*
X961200Y1585100D03*
X961700Y1578800D03*
X966900Y1579200D03*
X972800D03*
X961900Y1572400D03*
X967100Y1572800D03*
X972400Y1592000D03*
X966500D03*
X961300Y1591600D03*
X972200Y1598400D03*
X966300D03*
X961100Y1598000D03*
X960600Y1604300D03*
X971700Y1604700D03*
X965800D03*
X944499Y1632650D03*
X925599Y1612050D03*
X933199Y1577550D03*
X925499Y1562550D03*
X989999Y1718050D03*
X958799Y1715750D03*
X957799Y1646950D03*
X955499Y1690850D03*
X941499Y1679550D03*
X940499Y1656950D03*
X931499Y1702050D03*
X941800Y1787700D03*
X934200Y1793500D03*
X993299Y1734350D03*
X994999Y1748950D03*
X976600Y1757100D03*
X965349Y1742000D03*
X949799Y1756250D03*
X976399Y1772250D03*
X954499Y1783550D03*
X941499Y1776250D03*
X932199Y1801850D03*
X971000Y1803000D03*
X999999Y1775250D03*
X976399Y1791150D03*
X993499Y1805550D03*
X928000Y1818500D03*
X1003599Y1846650D03*
X995699Y1858950D03*
X971500Y1871500D03*
X937199Y1869950D03*
X993499Y1824550D03*
Y1833550D03*
X987999Y1971950D03*
Y1949050D03*
X1000999Y1946350D03*
X991999Y1915750D03*
X966799Y1892150D03*
X974699Y1914450D03*
X945199Y1946350D03*
X955799Y1951950D03*
X954099Y1915450D03*
X938199Y1917150D03*
X1002500Y1953500D03*
X1001599Y1921450D03*
X992299Y1929050D03*
X989999Y1962650D03*
X980999Y1933350D03*
X947499Y1936050D03*
X946199Y1966650D03*
X937499Y1893850D03*
X971499Y1956050D03*
Y1965050D03*
Y1937050D03*
X930999Y1950050D03*
X931499Y1962050D03*
X930999Y1931050D03*
X955499Y1893050D03*
Y1902050D03*
X953799Y1977950D03*
X930199Y1979550D03*
X1005000Y1980500D03*
X994999Y1986550D03*
X973999D03*
X956499Y1986050D03*
X936999Y1986550D03*
X1022000Y15500D03*
X1013499Y6550D03*
X1020499Y50550D03*
X1020999Y33050D03*
X1010599Y115550D03*
X1020499Y122550D03*
X1020999Y105050D03*
Y85550D03*
Y70050D03*
X1021499Y141050D03*
X1020999Y230550D03*
X1021499Y213050D03*
Y193550D03*
Y178050D03*
X1020999Y158550D03*
Y304550D03*
Y289050D03*
X1020499Y269550D03*
X1020999Y252050D03*
X1020499Y341550D03*
X1020999Y324050D03*
X1020499Y391550D03*
X1020999Y374050D03*
X1007299Y432450D03*
Y414950D03*
Y400450D03*
X1020499Y463550D03*
X1020999Y446050D03*
Y426550D03*
Y411050D03*
X1021999Y558550D03*
Y539050D03*
Y523550D03*
X1021499Y504050D03*
X1021999Y486550D03*
X1021499Y576050D03*
X1020999Y642550D03*
X1020499Y623050D03*
X1020999Y605550D03*
X1020499Y695050D03*
X1020999Y677550D03*
Y658050D03*
Y720050D03*
X1020499Y809550D03*
X1020999Y792050D03*
Y772550D03*
Y757050D03*
X1020499Y737550D03*
Y880550D03*
Y865050D03*
X1019999Y845550D03*
X1020499Y828050D03*
X1019999Y917550D03*
X1020499Y900050D03*
X1019999Y971050D03*
X1019499Y951550D03*
X1019999Y934050D03*
Y986550D03*
Y1058550D03*
Y1043050D03*
X1019499Y1023550D03*
X1019999Y1006050D03*
X1020499Y1134050D03*
Y1118550D03*
X1019999Y1099050D03*
X1020499Y1081550D03*
X1019499Y1198550D03*
Y1183050D03*
X1018999Y1163550D03*
X1019499Y1146050D03*
X1016999Y1219050D03*
X1016499Y1301050D03*
Y1236550D03*
X1016999Y1256050D03*
Y1271550D03*
X1023300Y1344400D03*
X1024300Y1365200D03*
X1022599Y1322950D03*
X1024300Y1393600D03*
X1008599Y1716050D03*
X1022299Y1715750D03*
X1008999Y1702450D03*
X1016899Y1731650D03*
X1026899Y1768550D03*
X1020299Y1746650D03*
X1015299Y1765950D03*
X1009999Y1797450D03*
X1022499Y1802050D03*
X1022999Y1784550D03*
X1011299Y1860650D03*
X1007599Y1818450D03*
X1022999Y1821550D03*
Y1837050D03*
X1020499Y1877550D03*
X1020999Y1860050D03*
Y1912550D03*
Y1897050D03*
X1017499Y1954550D03*
X1017999Y1937050D03*
Y1987050D03*
X1023000Y1973000D03*
G54D20*
G01X39217Y554750D02*
Y549981D01*
X39204Y549968D01*
Y546932D01*
X40186Y545950D01*
X40301Y545834D01*
Y530002D01*
X45613Y524690D01*
Y511910D01*
X43887Y510184D01*
Y430019D01*
X83994Y389912D01*
X345839D01*
X375999Y420072D01*
Y698550D01*
G01X371999Y549300D02*
Y421094D01*
X344367Y393462D01*
X85466D01*
X47437Y431491D01*
Y508712D01*
X49163Y510438D01*
Y526162D01*
X43851Y531474D01*
Y547466D01*
X42867Y548450D01*
G01X370149Y1320050D02*
Y888841D01*
X377887Y881103D01*
Y419449D01*
X346575Y388137D01*
X83258D01*
X42112Y429283D01*
Y510920D01*
X43838Y512646D01*
Y523954D01*
X38526Y529266D01*
Y538301D01*
X37461Y539366D01*
Y546164D01*
X37429Y546196D01*
Y549433D01*
X35974Y550886D01*
Y559575D01*
X33699Y561850D01*
G01X372999Y1123550D02*
X379662Y1116887D01*
Y418713D01*
X347311Y386362D01*
X82522D01*
X40337Y428547D01*
Y511656D01*
X42063Y513382D01*
Y523218D01*
X36751Y528530D01*
Y537564D01*
X35663Y538652D01*
Y545451D01*
X35654Y545460D01*
Y548696D01*
X34199Y550150D01*
Y557046D01*
X33307Y557938D01*
G01X26199Y547176D02*
Y541270D01*
X25311Y540382D01*
Y538818D01*
X29651Y534478D01*
Y524931D01*
X29714Y524867D01*
X29915Y522590D01*
Y515065D01*
X33163Y511817D01*
Y425677D01*
X79990Y378850D01*
X244799D01*
X284999Y338650D01*
G01X29999Y557150D02*
Y551695D01*
X33846Y547848D01*
Y537957D01*
X34976Y536827D01*
Y527794D01*
X40288Y522482D01*
Y514118D01*
X38562Y512392D01*
Y427811D01*
X81786Y384587D01*
X348047D01*
X381437Y417977D01*
Y1700263D01*
X377900Y1703800D01*
G01X371500Y880600D02*
X373887Y878213D01*
Y420471D01*
X345103Y391687D01*
X84730D01*
X45662Y430755D01*
Y509448D01*
X47388Y511174D01*
Y525426D01*
X42076Y530738D01*
Y546571D01*
X40979Y547668D01*
Y549232D01*
X41105Y549358D01*
Y558844D01*
X33899Y566050D01*
Y571550D01*
X28000Y577448D01*
Y578500D01*
G01X390999Y1517798D02*
X388545Y1515344D01*
Y420063D01*
X349519Y381037D01*
X80314D01*
X34938Y426413D01*
Y512553D01*
X31691Y515800D01*
Y523228D01*
X31636Y523282D01*
X31426Y525667D01*
Y535353D01*
X30280Y536499D01*
Y546391D01*
X29348Y547324D01*
X25581Y551091D01*
Y567763D01*
G01X27699Y573750D02*
X27766Y573683D01*
Y551417D01*
X32055Y547128D01*
Y537236D01*
X33201Y536090D01*
Y526403D01*
X33412Y526192D01*
Y524018D01*
X33466Y523964D01*
Y516536D01*
X36713Y513289D01*
Y427149D01*
X81050Y382812D01*
X348783D01*
X385499Y419528D01*
Y1735050D01*
G01X43099Y555850D02*
Y552584D01*
X45626Y550057D01*
Y532210D01*
X50938Y526898D01*
Y509702D01*
X49212Y507976D01*
Y432227D01*
X82323Y399116D01*
X347510D01*
X368162Y419768D01*
Y1742387D01*
X348499Y1762050D01*
G01X46299Y552950D02*
Y551895D01*
X47401Y550793D01*
Y532946D01*
X52713Y527634D01*
Y508966D01*
X50987Y507240D01*
Y432963D01*
X83059Y400891D01*
X346774D01*
X366387Y420504D01*
Y1553812D01*
X366149Y1554050D01*
G01X364499Y1099050D02*
Y421127D01*
X346038Y402666D01*
X99177D01*
X52762Y449081D01*
Y506504D01*
X54488Y508230D01*
Y528370D01*
X49176Y533682D01*
Y553673D01*
X36499Y566350D01*
G01X42599Y567850D02*
Y567301D01*
X47699Y562201D01*
Y557661D01*
X50951Y554409D01*
Y534418D01*
X56263Y529106D01*
Y506547D01*
X54537Y504821D01*
Y449817D01*
X99913Y404441D01*
X345302D01*
X346408Y405547D01*
Y684141D01*
X285499Y745050D01*
G01X47101Y632355D02*
X44900Y630154D01*
Y625000D01*
X36111Y616211D01*
Y577344D01*
X45355Y568100D01*
X48099D01*
X54501Y561698D01*
Y535890D01*
X59813Y530578D01*
Y504613D01*
X58113Y502913D01*
Y453142D01*
X69255Y442000D01*
X122549D01*
X141499Y423050D01*
G01X344520Y406329D02*
X116571D01*
X82675Y440225D01*
X68519D01*
X56312Y452432D01*
Y504085D01*
X58038Y505811D01*
Y529842D01*
X52726Y535154D01*
Y556223D01*
X49799Y559150D01*
G01X61400Y452600D02*
X59888Y454112D01*
Y492999D01*
X73515Y506626D01*
X73631D01*
X94012Y527007D01*
Y535707D01*
X86719Y543000D01*
X71500D01*
X68000Y546500D01*
G01X30500Y1395500D02*
X33170D01*
X34900Y1393770D01*
X37349Y1391322D01*
Y1052100D01*
X19575Y1034326D01*
Y1025300D01*
X37349Y1007526D01*
Y865349D01*
X27000Y855000D01*
Y818421D01*
X24411Y815832D01*
Y773389D01*
X29387Y768413D01*
Y702431D01*
X32887Y698931D01*
Y649768D01*
X32824Y649705D01*
Y613924D01*
X24866Y605966D01*
Y571966D01*
X20912Y568012D01*
Y521557D01*
X31388Y511081D01*
Y417112D01*
X35900Y412600D01*
G01X65000Y455500D02*
X61663Y458837D01*
Y492129D01*
X95787Y526253D01*
Y536443D01*
X87230Y545000D01*
X72500D01*
G01X78600Y1561900D02*
X76950Y1560250D01*
Y1550691D01*
X53424Y1527165D01*
Y854947D01*
X44571Y846094D01*
Y809471D01*
X33412Y798312D01*
Y785788D01*
X36437Y782763D01*
Y643076D01*
X36412Y643051D01*
Y630172D01*
X39600Y626984D01*
G01X42709Y625607D02*
X42198Y625096D01*
X38818D01*
X34637Y629277D01*
Y644137D01*
X34662Y644162D01*
Y699914D01*
X31637Y702939D01*
Y799295D01*
X33504Y801162D01*
X33582D01*
X34688Y802268D01*
Y802346D01*
X42621Y810279D01*
Y846795D01*
X51549Y855723D01*
Y1527943D01*
X75000Y1551394D01*
Y1561800D01*
G01X38300Y633800D02*
X39612Y635112D01*
Y643582D01*
X42605Y646575D01*
X65732D01*
X78028Y658871D01*
X79628D01*
X203806Y783049D01*
X325772D01*
X350987Y808264D01*
Y1525518D01*
X349711Y1526794D01*
Y1582837D01*
X349774Y1582900D01*
G01X107000Y604800D02*
X104500Y602300D01*
X78700D01*
X71100Y609900D01*
X49026D01*
X47626Y611300D01*
G01X45701Y607700D02*
X70542D01*
X78449Y599793D01*
X104893D01*
X105100Y600000D01*
G01X188000Y484500D02*
X176382D01*
X170499Y490383D01*
Y500550D01*
X158936Y512113D01*
Y587987D01*
X164688Y593739D01*
Y651450D01*
X155682Y660456D01*
X124056D01*
X90650Y627050D01*
X82499D01*
G01X48999Y642900D02*
X50349Y644250D01*
X65918D01*
X78764Y657096D01*
X80364D01*
X204542Y781274D01*
X326508D01*
X352762Y807528D01*
Y1531276D01*
X352612Y1531426D01*
Y1560282D01*
X354087Y1561757D01*
Y1584813D01*
X354000Y1584900D01*
G01X48999Y642900D02*
Y638501D01*
X52500Y635000D01*
G01X327999Y740550D02*
X360182Y772733D01*
Y1711459D01*
X355753Y1715888D01*
X355133D01*
X301033Y1769988D01*
X69288D01*
X68975Y1769675D01*
X68438D01*
X49213Y1750450D01*
X48802D01*
X48789Y1750437D01*
X45023D01*
X44011Y1749425D01*
X40905D01*
X39312Y1747832D01*
Y1744806D01*
X33187Y1738681D01*
Y1718310D01*
X54085Y1697412D01*
Y1581173D01*
X55088Y1580170D01*
Y1563423D01*
X45418Y1553753D01*
X44432D01*
X40849Y1550170D01*
Y1539632D01*
X36174Y1534957D01*
Y1531745D01*
X36111Y1531682D01*
Y1529181D01*
X44449Y1520843D01*
Y858667D01*
X34962Y849180D01*
Y814943D01*
X32800Y812781D01*
Y803050D01*
G01X46887Y803413D02*
Y805887D01*
X52186Y811186D01*
Y845185D01*
X58800Y851799D01*
Y852543D01*
X58924Y852667D01*
Y1041395D01*
X111519Y1093990D01*
X120749D01*
G01X27299Y783550D02*
Y812620D01*
X33187Y818508D01*
Y849916D01*
X42674Y859403D01*
Y1520107D01*
X34336Y1528445D01*
Y1532418D01*
X34399Y1532481D01*
Y1535693D01*
X39074Y1540368D01*
Y1550906D01*
X43696Y1555528D01*
X44682D01*
X53313Y1564159D01*
Y1579434D01*
X52310Y1580437D01*
Y1696676D01*
X31412Y1717574D01*
Y1739417D01*
X34966Y1742971D01*
Y1751361D01*
X39493Y1755888D01*
X44891D01*
X45017Y1755762D01*
X46992D01*
X60724Y1769494D01*
Y1790264D01*
X73981Y1803522D01*
X74159Y1803787D01*
X74875Y1804503D01*
X75140Y1804681D01*
X76047Y1805587D01*
X76364Y1805650D01*
X123064D01*
X123381Y1805587D01*
X140705Y1788263D01*
X204489D01*
X204727Y1788025D01*
X345735D01*
X404175Y1729585D01*
Y1577555D01*
X404662Y1577068D01*
Y1574032D01*
X404474Y1573844D01*
Y79525D01*
X381999Y57050D01*
G01X45100Y793100D02*
Y797300D01*
X65500Y817700D01*
G01X37216Y807951D02*
X38987Y809722D01*
Y812132D01*
X36737Y814382D01*
Y848444D01*
X46224Y857931D01*
Y1530151D01*
X63963Y1547890D01*
Y1636523D01*
X62960Y1637526D01*
Y1640664D01*
X63523Y1641227D01*
Y1681023D01*
X74500Y1692000D01*
G01X90000Y993100D02*
Y990700D01*
X73286Y973986D01*
Y857754D01*
X76540Y854500D01*
Y850938D01*
G01X331622Y1944767D02*
X332000Y1944389D01*
Y1930900D01*
X273451Y1872351D01*
X135954D01*
X126315Y1862712D01*
X52259D01*
X51548Y1862001D01*
X51547D01*
X34628Y1845082D01*
Y1842415D01*
X24211Y1831998D01*
Y1819873D01*
X28647Y1815437D01*
X28685Y1815245D01*
Y1804756D01*
X22150Y1798221D01*
Y1747732D01*
X18812Y1744394D01*
Y1712497D01*
X19236Y1712073D01*
Y1712072D01*
X25758Y1705550D01*
X25759D01*
X38547Y1692762D01*
Y1614216D01*
X38536Y1614205D01*
Y1598919D01*
X40723Y1596732D01*
Y1576958D01*
X42663Y1575018D01*
Y1569115D01*
X39726Y1566178D01*
X36017D01*
X27701Y1557862D01*
Y1545286D01*
X24817Y1542402D01*
Y1534013D01*
X34493Y1524337D01*
X35933D01*
X40899Y1519371D01*
Y860139D01*
X29299Y848539D01*
Y836901D01*
G01X92600Y996100D02*
X90330D01*
X88050Y993820D01*
Y991261D01*
X71511Y974722D01*
Y853209D01*
X75500Y849220D01*
Y847700D01*
G01X40400Y840792D02*
Y840951D01*
X40475Y841026D01*
Y847160D01*
X49774Y856459D01*
Y1528679D01*
X67561Y1546466D01*
Y1562361D01*
X83600Y1578400D01*
X92800D01*
X134915Y1620515D01*
Y1699114D01*
X134978Y1699177D01*
Y1700741D01*
X134915Y1700804D01*
Y1707134D01*
X131999Y1710050D01*
G01X89000Y816500D02*
X88112Y817388D01*
Y831782D01*
X94543Y838213D01*
X152298D01*
X152461Y838050D01*
X154799D01*
G01X106162Y1205702D02*
X57149Y1156689D01*
Y1039803D01*
X57148Y1039802D01*
Y1036860D01*
X57149Y1036859D01*
Y853332D01*
X48346Y844529D01*
G01X345424Y1310050D02*
Y1100324D01*
X343611Y1098511D01*
Y1060662D01*
X337374Y1054425D01*
Y963331D01*
X186855Y812812D01*
X143288D01*
X130100Y826000D01*
X90000D01*
G01X54074Y815750D02*
X60699Y822375D01*
Y1038420D01*
X106191Y1083912D01*
X106781D01*
X110444Y1087575D01*
X127027D01*
X130125Y1084477D01*
Y1068207D01*
X132307Y1066025D01*
X160814D01*
X194350Y1099561D01*
X194624Y1100223D01*
Y1173175D01*
X326500Y1305051D01*
Y1550200D01*
G01X90500Y831500D02*
X95438Y836438D01*
X149662D01*
X153900Y832200D01*
G01X39649Y822000D02*
X38512Y823137D01*
Y847708D01*
X47999Y857195D01*
Y1529415D01*
X65738Y1547154D01*
Y1575638D01*
X74800Y1584700D01*
G01X25000Y858100D02*
X25882D01*
X28987Y861205D01*
Y875456D01*
X21711Y882732D01*
Y1020389D01*
X17800Y1024300D01*
Y1035062D01*
X28988Y1046250D01*
Y1353754D01*
X25000Y1357742D01*
G01X46576Y832951D02*
X46458Y833069D01*
Y845311D01*
X55199Y854052D01*
Y1410051D01*
X76000Y1430852D01*
Y1431100D01*
G01X29600Y854000D02*
X39124Y863524D01*
Y1504376D01*
X37200Y1506300D01*
X29400D01*
X26200Y1509500D01*
Y1521699D01*
X24199Y1523700D01*
G01X94999Y901550D02*
X111999Y918550D01*
X153499D01*
G01X63500Y1029600D02*
X63549D01*
X103449Y1069500D01*
X105600D01*
G01X77758Y1357742D02*
X63023Y1372477D01*
Y1405179D01*
X62960Y1405242D01*
Y1408380D01*
X63023Y1408443D01*
Y1415364D01*
X77775Y1430116D01*
Y1430205D01*
X77888Y1430318D01*
Y1432612D01*
X57199Y1453301D01*
Y1522073D01*
X58976Y1526364D01*
X87375Y1554763D01*
Y1555081D01*
X89373Y1561073D01*
G01X76000Y1431100D02*
X55424Y1451676D01*
Y1525323D01*
X85600Y1555499D01*
Y1561500D01*
G01X34896Y1555730D02*
X34452Y1556174D01*
Y1559591D01*
X37489Y1562628D01*
X41198D01*
X46213Y1567643D01*
Y1576490D01*
X45210Y1577493D01*
Y1693632D01*
X24137Y1714705D01*
Y1742186D01*
X27475Y1745524D01*
Y1795860D01*
X34112Y1802497D01*
Y1806182D01*
X41001Y1813071D01*
Y1822579D01*
X59084Y1840662D01*
X61231D01*
X67882Y1847313D01*
X135067D01*
X135630Y1846750D01*
X553401D01*
X824288Y1575863D01*
X824290Y1575862D01*
X829354D01*
X912257Y1492959D01*
Y546957D01*
X789999Y424699D01*
Y336550D01*
G01X46700Y1546793D02*
Y1547502D01*
X60413Y1561215D01*
Y1582378D01*
X59410Y1583381D01*
Y1699620D01*
X38512Y1720518D01*
Y1736382D01*
X42529Y1740399D01*
X45029D01*
X47966Y1743336D01*
X51732D01*
X51745Y1743349D01*
X52156D01*
X70756Y1761949D01*
X94951D01*
X102575Y1754325D01*
X185009D01*
X328388Y1610946D01*
Y1304428D01*
X196399Y1172439D01*
Y1099487D01*
X196125Y1098825D01*
X161550Y1064250D01*
X131571D01*
X128350Y1067471D01*
Y1080924D01*
X123786Y1085488D01*
X116156D01*
X106718Y1076050D01*
G01X282099Y745050D02*
Y761244D01*
X294255Y773400D01*
X323656D01*
X356388Y806132D01*
Y1710231D01*
X354281Y1712338D01*
X353661D01*
X299561Y1766438D01*
X70760D01*
X70447Y1766125D01*
X69910D01*
X50684Y1746899D01*
X50273D01*
X50261Y1746887D01*
X46495D01*
X43558Y1743950D01*
X41057D01*
X38146Y1741039D01*
Y1741038D01*
X34962Y1737854D01*
Y1719046D01*
X55860Y1698148D01*
Y1581909D01*
X56863Y1580906D01*
Y1562687D01*
X46154Y1551978D01*
X45327D01*
X44299Y1550950D01*
G01X37999Y1530900D02*
X62188Y1555089D01*
Y1583114D01*
X61748Y1583554D01*
Y1603328D01*
X61185Y1603891D01*
Y1641400D01*
X61748Y1641963D01*
Y1683748D01*
X92400Y1714400D01*
X101787D01*
X104000Y1716613D01*
X112753D01*
G01X200799Y896600D02*
Y903785D01*
X310898Y1013884D01*
Y1066450D01*
X313000Y1068553D01*
X337124Y1092677D01*
Y1611456D01*
X186005Y1762575D01*
X138800D01*
X137588Y1763787D01*
X70083D01*
X51407Y1745111D01*
X47230D01*
X44293Y1742174D01*
X41793D01*
X36737Y1737118D01*
Y1719782D01*
X57635Y1698884D01*
Y1582645D01*
X58638Y1581642D01*
Y1561951D01*
X42624Y1545937D01*
Y1538724D01*
X38500Y1534600D01*
G01X32099Y1535550D02*
X32624Y1536075D01*
Y1536429D01*
X37299Y1541104D01*
Y1552272D01*
X42330Y1557303D01*
X43946D01*
X51538Y1564895D01*
Y1578698D01*
X50535Y1579701D01*
Y1695840D01*
X29462Y1716913D01*
Y1739978D01*
X32801Y1743317D01*
Y1751707D01*
X40357Y1759263D01*
X40446D01*
X40749Y1759566D01*
X46595D01*
X46658Y1759503D01*
X48222D01*
X49328Y1760609D01*
Y1760698D01*
X58824Y1770194D01*
Y1813112D01*
X68486Y1822774D01*
X512275D01*
X791499Y1543550D01*
G01X789499Y1138050D02*
X789111Y1138438D01*
X783657D01*
X773381Y1128162D01*
X771717D01*
X769145Y1130734D01*
Y1341204D01*
X860715Y1432774D01*
Y1499053D01*
X860036Y1499732D01*
Y1512324D01*
X856101Y1516259D01*
X542490Y1829871D01*
X73072D01*
X57049Y1813848D01*
Y1772229D01*
X48120Y1763300D01*
X41883D01*
X31025Y1752442D01*
Y1744052D01*
X27687Y1740714D01*
Y1716177D01*
X48760Y1695104D01*
Y1578965D01*
X49763Y1577962D01*
Y1566171D01*
X42670Y1559078D01*
X41594D01*
X35524Y1553008D01*
Y1543614D01*
X26705Y1534795D01*
G01X792499Y1949050D02*
X777499D01*
X693011Y1864562D01*
X146464D01*
X142738Y1868288D01*
X137510D01*
X137357Y1868185D01*
X128334Y1859162D01*
X53731D01*
X53020Y1858451D01*
X53019D01*
X38178Y1843610D01*
Y1840943D01*
X31900Y1834665D01*
Y1819811D01*
X30460Y1818371D01*
Y1803867D01*
X23925Y1797332D01*
Y1746996D01*
X20587Y1743658D01*
Y1713233D01*
X40322Y1693498D01*
Y1613480D01*
X40311Y1613469D01*
Y1599655D01*
X42498Y1597468D01*
Y1577694D01*
X44438Y1575754D01*
Y1568379D01*
X40462Y1564403D01*
X36753D01*
X30199Y1557849D01*
Y1545450D01*
G01X788999Y736050D02*
Y787548D01*
X905157Y903706D01*
Y1482121D01*
X868336Y1518942D01*
Y1519307D01*
X550634Y1837009D01*
X85721D01*
X82517Y1840213D01*
X70826D01*
X60166Y1829553D01*
X58019D01*
X48101Y1819635D01*
Y1806000D01*
X42999Y1800898D01*
Y1795671D01*
X41260Y1793932D01*
X41211D01*
X40199Y1792920D01*
Y1784850D01*
X29250Y1773901D01*
Y1744788D01*
X25912Y1741450D01*
Y1715441D01*
X46985Y1694368D01*
Y1578229D01*
X47988Y1577226D01*
Y1566907D01*
X41934Y1560853D01*
X38384D01*
X36340Y1558809D01*
G01X42199Y1601050D02*
Y1694132D01*
X22362Y1713969D01*
Y1742922D01*
X25700Y1746260D01*
Y1796596D01*
X32235Y1803131D01*
Y1817006D01*
X64317Y1849088D01*
X135803D01*
X136366Y1848525D01*
X800918D01*
X967600Y1681843D01*
Y1651100D01*
G01X284999Y1947691D02*
X278046D01*
X260100Y1929745D01*
Y1910981D01*
X223245Y1874126D01*
X134975D01*
X125336Y1864487D01*
X51523D01*
X50812Y1863776D01*
X50811D01*
X32853Y1845818D01*
Y1843151D01*
X22436Y1832734D01*
Y1819137D01*
X26872Y1814701D01*
X26910Y1814509D01*
Y1805492D01*
X20375Y1798957D01*
Y1748468D01*
X12711Y1740804D01*
Y1716086D01*
X36772Y1692025D01*
Y1614952D01*
X36761Y1614941D01*
Y1598183D01*
X38948Y1595996D01*
Y1576222D01*
X40888Y1574282D01*
Y1569851D01*
X38990Y1567953D01*
X35281D01*
X30678Y1563350D01*
X25521D01*
G01X21600Y1702900D02*
X31000Y1693500D01*
Y1675000D01*
X32700Y1673300D01*
G01X30274Y1787238D02*
X29923Y1787589D01*
Y1792304D01*
X35215Y1797596D01*
Y1801089D01*
X42776Y1808650D01*
Y1821843D01*
X59820Y1838887D01*
X61967D01*
X68618Y1845538D01*
X134331D01*
X134894Y1844975D01*
X552665D01*
X910482Y1487158D01*
Y548071D01*
X770290Y407879D01*
Y343259D01*
X791499Y322050D01*
Y296351D01*
X818800Y269050D01*
X849950D01*
X854400Y264600D01*
G01X402499Y1476850D02*
Y1574291D01*
X402699Y1574491D01*
Y1574580D01*
X402887Y1574768D01*
Y1576332D01*
X402399Y1576820D01*
Y1728850D01*
X344999Y1786250D01*
X203991D01*
X203753Y1786488D01*
X199245D01*
X199007Y1786250D01*
X118799D01*
X107699Y1797350D01*
X85599D01*
G01X852333Y1077716D02*
X857437D01*
X901607Y1121886D01*
Y1475774D01*
X868185Y1509196D01*
X864200Y1513180D01*
Y1513182D01*
X544668Y1832715D01*
X544405Y1832978D01*
X544110Y1833421D01*
X69056D01*
X61638Y1826003D01*
X59491D01*
X51651Y1818163D01*
Y1802402D01*
X47899Y1798650D01*
G01X350499Y715050D02*
X361957Y726508D01*
Y1712195D01*
X356489Y1717663D01*
X355869D01*
X298231Y1775301D01*
X71553D01*
X48464Y1752212D01*
X44287D01*
X43775Y1751700D01*
X39900D01*
X39000Y1750800D01*
G01X42275Y1754000D02*
X44268D01*
X44281Y1753987D01*
X47317D01*
X47330Y1754000D01*
X47741D01*
X72512Y1778771D01*
Y1778882D01*
X76330Y1782700D01*
X200479D01*
X200717Y1782938D01*
X202281D01*
X202519Y1782700D01*
X343030D01*
X396474Y1729256D01*
Y631445D01*
X396537Y631382D01*
Y629818D01*
X396474Y629755D01*
Y408336D01*
X395949Y407811D01*
Y388432D01*
X288631Y281114D01*
X225298D01*
G01X37699Y1789850D02*
X35686Y1791863D01*
Y1795556D01*
X36990Y1796860D01*
Y1800353D01*
X44551Y1807914D01*
Y1821107D01*
X56547Y1833103D01*
X58694D01*
X69354Y1843763D01*
X94616D01*
X97217Y1841162D01*
X98781D01*
X100779Y1843160D01*
X551969D01*
X908707Y1486422D01*
Y548810D01*
X768515Y408618D01*
Y337738D01*
X772873Y333380D01*
Y326924D01*
G01X326499Y337454D02*
X392399Y403354D01*
Y409283D01*
X392774Y409658D01*
Y629805D01*
X392761Y629818D01*
Y631382D01*
X392887Y631508D01*
Y1730332D01*
X345119Y1778100D01*
X74400D01*
G01X41200Y1747050D02*
X44147D01*
X45759Y1748662D01*
X49936D01*
X69174Y1767900D01*
X69711D01*
X70024Y1768213D01*
X300297D01*
X354397Y1714113D01*
X355017D01*
X358163Y1710967D01*
Y774464D01*
X327749Y744050D01*
G01X42199Y1792250D02*
X44774Y1794825D01*
Y1800162D01*
X49876Y1805264D01*
Y1818899D01*
X58755Y1827778D01*
X60902D01*
X71562Y1838438D01*
X81781D01*
X85023Y1835196D01*
X544846D01*
X545551Y1834491D01*
X545582Y1834415D01*
X545786Y1834108D01*
X545921Y1833973D01*
X865975Y1513918D01*
Y1513916D01*
X867602Y1512290D01*
X903382Y1476510D01*
Y904442D01*
X769008Y770068D01*
Y734041D01*
X769999Y733050D01*
G01X46799Y1794900D02*
X48100D01*
X53426Y1800226D01*
Y1817427D01*
X60227Y1824228D01*
X62374D01*
X69792Y1831646D01*
X543225D01*
X543415Y1831457D01*
X861811Y1513060D01*
Y1500468D01*
X862490Y1499789D01*
Y1432038D01*
X773521Y1343069D01*
Y1131072D01*
X772499Y1130050D01*
G01X47400Y1765250D02*
X47559D01*
X55274Y1772965D01*
Y1814584D01*
X55399Y1814709D01*
Y1815561D01*
X60896Y1821058D01*
Y1822227D01*
X61009Y1822340D01*
G01X40478Y1795820D02*
X40766Y1796108D01*
Y1801176D01*
X46326Y1806736D01*
Y1820371D01*
X57283Y1831328D01*
X59430D01*
X70090Y1841988D01*
X93880D01*
X97084Y1838784D01*
X551370D01*
X870111Y1520043D01*
Y1519678D01*
X906932Y1482857D01*
Y721674D01*
X856455Y671197D01*
X852696D01*
G01X227814Y1887513D02*
X216401Y1876100D01*
X134438D01*
X124600Y1866262D01*
X50787D01*
X50076Y1865551D01*
X50075D01*
X29599Y1845075D01*
Y1844350D01*
G01X381999Y53550D02*
X406124Y77675D01*
Y78664D01*
X406249Y78789D01*
Y1573108D01*
X406437Y1573296D01*
Y1577804D01*
X406249Y1577992D01*
Y1729845D01*
X405950Y1730144D01*
Y1730321D01*
X346471Y1789800D01*
X346117D01*
X316693Y1819224D01*
X93224D01*
X88400Y1814400D01*
X82949D01*
X80099Y1817250D01*
G01X28123Y1831527D02*
Y1833399D01*
X36403Y1841679D01*
Y1844346D01*
X52283Y1860226D01*
X52284D01*
X52995Y1860937D01*
X127597D01*
X137130Y1870470D01*
X137287Y1870576D01*
X274373D01*
X333798Y1930001D01*
Y1946438D01*
X332103Y1948133D01*
G01X86649Y1817100D02*
X90548Y1820999D01*
X492370D01*
X774577Y1538792D01*
Y1533796D01*
G01X36532Y1825352D02*
X34511Y1827373D01*
Y1834765D01*
X39953Y1840207D01*
Y1842874D01*
X53755Y1856676D01*
X53756D01*
X54467Y1857387D01*
X139066D01*
X140179Y1858500D01*
X142619D01*
X145672Y1861553D01*
X692510D01*
X692608Y1861651D01*
X692611D01*
X692732Y1861772D01*
X693221D01*
X771499Y1940050D01*
G01X36399Y1828750D02*
Y1834142D01*
X41728Y1839471D01*
Y1842138D01*
X54491Y1854901D01*
X54492D01*
X54866Y1855275D01*
X137706D01*
X139103Y1853878D01*
X145278D01*
X150950Y1859550D01*
X830814D01*
X854814Y1883550D01*
G01X969600Y1638300D02*
Y1682354D01*
X801654Y1850300D01*
X137102D01*
X136539Y1850863D01*
X55475D01*
X45278Y1840666D01*
Y1837999D01*
X43099Y1835820D01*
Y1833850D01*
G01X39699D02*
Y1834931D01*
X43503Y1838735D01*
Y1841402D01*
X55601Y1853500D01*
X136675D01*
X138072Y1852103D01*
X802362D01*
X971558Y1682907D01*
Y1646500D01*
G01X97499Y90050D02*
Y125425D01*
X116124Y144050D01*
X231999D01*
X282800Y93249D01*
Y87500D01*
G01X141499Y427550D02*
Y435618D01*
X153319Y447438D01*
X155642D01*
X199900Y491696D01*
Y554050D01*
G01X159600Y446399D02*
X212999Y499798D01*
Y512636D01*
X216763Y516400D01*
X220000D01*
G01X135499Y517550D02*
X131499D01*
X129924Y515975D01*
X129908D01*
X110983Y497050D01*
X107499D01*
G01X172499Y491053D02*
Y496470D01*
X177579Y501550D01*
Y659647D01*
X293108Y775176D01*
X322921D01*
X354537Y806792D01*
Y1532012D01*
X354500Y1532049D01*
Y1559500D01*
G01X107000Y604800D02*
X107300Y604500D01*
Y597600D01*
X106000Y596300D01*
Y546600D01*
X109400Y543200D01*
G01X105100Y600000D02*
Y599600D01*
X104225Y598725D01*
Y544975D01*
X106000Y543200D01*
G01X110202Y813379D02*
X103575Y806752D01*
Y791944D01*
X109694Y785825D01*
X326037D01*
X349212Y809000D01*
Y1524782D01*
X346911Y1527083D01*
Y1703862D01*
X353499Y1710450D01*
G01X329499Y801550D02*
X320874Y792925D01*
X312618D01*
X307443Y798100D01*
X188575D01*
X183400Y792925D01*
X117725D01*
X111200Y799450D01*
G01X347324Y1524000D02*
X347437Y1523887D01*
Y809736D01*
X325301Y787600D01*
X110696D01*
X109984Y788312D01*
X109718D01*
X108612Y789418D01*
Y789684D01*
X105350Y792946D01*
Y805134D01*
X110195Y809979D01*
G01X330540Y795509D02*
X330458D01*
X324324Y789375D01*
X111432D01*
X110720Y790087D01*
X110613D01*
X110500Y790200D01*
G01X320499Y798050D02*
X310004D01*
X306716Y801338D01*
X110418D01*
X109312Y800232D01*
Y797188D01*
X110700Y795800D01*
Y795700D01*
G01X340699Y1046086D02*
X339149Y1044536D01*
Y961315D01*
X185434Y807600D01*
X111600D01*
X110598Y806598D01*
X109831D01*
G01X345499Y1096550D02*
Y814699D01*
X321950Y791150D01*
X112669D01*
X110007Y793812D01*
X109918D01*
X108812Y794918D01*
Y795007D01*
X107125Y796694D01*
Y800709D01*
X109616Y803200D01*
X109700D01*
G01X165499Y815550D02*
X146499Y834550D01*
X110499D01*
G01X169106Y815865D02*
Y818806D01*
X312673Y962373D01*
Y1065149D01*
X338899Y1091375D01*
Y1612192D01*
X186741Y1764350D01*
X142199D01*
X141999Y1764550D01*
G01X171100Y935000D02*
X177100D01*
X309123Y1067023D01*
Y1067185D01*
X311744Y1069809D01*
X335349Y1093414D01*
Y1265406D01*
X331161Y1269594D01*
Y1482806D01*
X335349Y1486994D01*
Y1610720D01*
X186194Y1759875D01*
X110099D01*
G01X116700Y1063500D02*
Y1019800D01*
X155463Y981037D01*
X155531D01*
X156637Y979931D01*
Y979863D01*
X171450Y965050D01*
Y961550D01*
X172000Y961000D01*
G01X152500Y960000D02*
X104600Y1007900D01*
Y1050875D01*
X112699Y1058974D01*
G01X123999Y1102550D02*
X129400Y1097149D01*
Y1090500D01*
X132000Y1087900D01*
Y1068843D01*
X133043Y1067800D01*
X160078D01*
X162811Y1070533D01*
Y1076456D01*
X164093Y1077738D01*
X170016D01*
X192845Y1100567D01*
X192849Y1100576D01*
Y1173911D01*
X324200Y1305262D01*
Y1556100D01*
X326074Y1557974D01*
Y1610749D01*
X184273Y1752550D01*
X101024D01*
X99999Y1753575D01*
G01X123970Y1221573D02*
X125522D01*
X179449Y1275500D01*
X182500D01*
G01X157400Y1596550D02*
X97499Y1554550D01*
G01X96999Y1558050D02*
X156000Y1598500D01*
X160200D01*
G01X150999Y1713550D02*
X151950D01*
X171999Y1693501D01*
Y1662250D01*
G01X99199Y1761899D02*
X104998Y1756100D01*
X185745D01*
X185845Y1756000D01*
X187558D01*
X330300Y1613258D01*
Y1561200D01*
G01X101399Y1784700D02*
X117838D01*
X118063Y1784475D01*
X199743D01*
X199981Y1784713D01*
X203017D01*
X203255Y1784475D01*
X343800D01*
X398249Y1730026D01*
Y632181D01*
X398312Y632118D01*
Y629082D01*
X398249Y629019D01*
Y407600D01*
X397724Y407075D01*
Y197775D01*
X297499Y97550D01*
G01X854327Y1477550D02*
Y1510128D01*
X841811Y1522644D01*
Y1528038D01*
X840961Y1528888D01*
X541754Y1828096D01*
X98696D01*
X96600Y1826000D01*
G01X183499Y556100D02*
X284200Y656801D01*
Y724349D01*
X279939Y728610D01*
G01X257499Y1911050D02*
Y1933399D01*
X282650Y1958550D01*
X308999D01*
X310499Y1957050D01*
G01X341499Y63050D02*
X342974Y64525D01*
Y65915D01*
X343387Y66328D01*
Y67892D01*
X342974Y68305D01*
Y137014D01*
X401274Y195314D01*
Y195491D01*
X402323Y196540D01*
G03X402499Y196965I-425J425D01*
G01Y1462650D01*
X400611Y1464538D01*
Y1574914D01*
X400999Y1575302D01*
Y1575550D01*
G01X341499Y67110D02*
X340599Y68010D01*
Y137150D01*
X399499Y196050D01*
Y405329D01*
X400499Y406329D01*
G01X326499Y334054D02*
X394174Y401729D01*
Y408547D01*
X394549Y408922D01*
Y630500D01*
X394649Y630600D01*
G01X390999Y1514398D02*
Y632131D01*
X390986Y632118D01*
Y418864D01*
X308884Y336762D01*
X283287D01*
X281499Y338550D01*
G01X780499Y330050D02*
Y277050D01*
X837999Y219550D01*
G01X781999Y725550D02*
X780200Y723751D01*
Y661590D01*
X885740Y556050D01*
X902999D01*
G01X900499Y962100D02*
X897100D01*
X779499Y1079701D01*
Y1131050D01*
G54D11*
X8750Y1086250D03*
X93999Y58550D03*
X92900Y66128D03*
X89800Y132400D03*
X92999Y86128D03*
Y96128D03*
X74499Y84050D03*
Y80650D03*
X74999Y74050D03*
Y70550D03*
X78700Y70700D03*
Y74200D03*
X41999Y200050D03*
X24300Y247300D03*
X29699Y388484D03*
X29599Y382884D03*
X29999Y398684D03*
X23499Y397579D03*
X23399Y373931D03*
Y389679D03*
X23499Y381831D03*
X64403Y471046D03*
X64397Y474446D03*
X29899Y404384D03*
X28900Y429200D03*
X29365Y421169D03*
X29500Y460800D03*
X28700Y451900D03*
X28800Y436700D03*
X28700Y445700D03*
X68000Y475600D03*
X67800Y469900D03*
X23499Y468447D03*
X23399Y476295D03*
Y444799D03*
X23499Y452699D03*
X23399Y460547D03*
Y429051D03*
X23499Y436951D03*
X23600Y405700D03*
X77499Y469550D03*
X61400Y452600D03*
X35900Y412600D03*
X65000Y455500D03*
X39217Y554750D03*
X42867Y548450D03*
X43099Y555850D03*
X33699Y561850D03*
X46299Y552950D03*
X64600Y486300D03*
X64700Y489700D03*
X33307Y557938D03*
X26199Y547176D03*
X93200Y510500D03*
X83700Y529500D03*
X28600Y508500D03*
X88999Y538050D03*
X68900Y490600D03*
X68700Y485200D03*
X28600Y499300D03*
X26900Y532800D03*
X63499Y538550D03*
Y533050D03*
X23499Y515691D03*
X23399Y523539D03*
X23499Y531439D03*
X23399Y492043D03*
X23499Y499943D03*
X23399Y507791D03*
X23499Y484195D03*
X77999Y493050D03*
X77499Y502550D03*
X29999Y557150D03*
X60003Y534150D03*
X86199Y536025D03*
X59999Y537550D03*
X86199Y532250D03*
X49799Y559150D03*
X68000Y546500D03*
X72500Y545000D03*
X39600Y626984D03*
X42709Y625607D03*
X38300Y633800D03*
X36499Y566350D03*
X42599Y567850D03*
X32800Y578200D03*
X47543Y578340D03*
X44959Y575756D03*
X30712Y624971D03*
X29999Y640550D03*
X60076Y595777D03*
X55499Y595650D03*
X29819Y634951D03*
X26869Y616861D03*
X23399Y641649D03*
X23499Y618053D03*
X23799Y625950D03*
X23499Y633801D03*
X23999Y609250D03*
X22978Y588571D03*
X22699Y577950D03*
X57800Y634300D03*
X34976Y619250D03*
X44900Y642800D03*
X47101Y632355D03*
X28000Y578500D03*
X25581Y567763D03*
X47626Y611300D03*
X45701Y607700D03*
X27699Y573750D03*
X82499Y627050D03*
X52500Y635000D03*
X48999Y642900D03*
X81251Y607249D03*
Y619251D03*
X30999Y656250D03*
X29999Y694550D03*
X30999Y650550D03*
X81999Y668050D03*
X74499Y662050D03*
X25999Y694870D03*
X23999Y689050D03*
X23499Y665297D03*
X23699Y673150D03*
X23499Y681045D03*
Y649549D03*
X23725Y657471D03*
X78499Y654050D03*
X50410Y695801D03*
X50300Y699200D03*
X32800Y803050D03*
X46887Y803413D03*
X27299Y783550D03*
X45100Y793100D03*
X37216Y807951D03*
X76540Y850938D03*
X29299Y836901D03*
X75500Y847700D03*
X40400Y840792D03*
X89000Y816500D03*
X48346Y844529D03*
X92999Y868550D03*
X92499Y876550D03*
X90000Y826000D03*
X54074Y815750D03*
X90500Y831500D03*
X65500Y817700D03*
X39649Y822000D03*
X25000Y858100D03*
X46576Y832951D03*
X29600Y854000D03*
X89400Y935400D03*
X89499Y942850D03*
X94999Y901550D03*
X90000Y993100D03*
X92600Y996100D03*
X20400Y1048300D03*
X63500Y1029600D03*
X80000Y1090500D03*
X80500Y1097550D03*
Y1104500D03*
X21817Y1156317D03*
X78499Y1273550D03*
X78613Y1282664D03*
X78779Y1302664D03*
X91279Y1340642D03*
X89999Y1348050D03*
X27499Y1387550D03*
X24499Y1389663D03*
X22851Y1374169D03*
X22999Y1366050D03*
X23700Y1354600D03*
X23499Y1381500D03*
X78779Y1312664D03*
X86165Y1339050D03*
X77758Y1357742D03*
X25000D03*
X33000Y1393000D03*
X33400Y1408100D03*
X36198Y1446749D03*
X26800Y1443800D03*
X30600Y1415100D03*
X30999Y1438050D03*
X27999Y1430050D03*
X29100Y1459200D03*
X34200Y1466200D03*
X23028Y1468579D03*
X23499Y1460550D03*
X22999Y1453050D03*
X23499Y1445050D03*
X22999Y1437050D03*
X23999Y1429050D03*
X23499Y1421550D03*
X23999Y1413550D03*
X30500Y1395500D03*
X76000Y1431100D03*
X34896Y1555730D03*
X46700Y1546793D03*
X44299Y1550950D03*
X32700Y1485200D03*
X28999Y1478050D03*
X27100Y1494300D03*
X34900Y1501000D03*
X35400Y1522200D03*
X35999Y1514550D03*
X29600Y1515300D03*
X24423Y1527123D03*
X22999Y1500050D03*
Y1515550D03*
X23799Y1508050D03*
X24499Y1492050D03*
X23599Y1476350D03*
X23277Y1484050D03*
X37999Y1530900D03*
X38500Y1534600D03*
X32099Y1535550D03*
X26705Y1534795D03*
X30199Y1545450D03*
X24199Y1523700D03*
X36340Y1558809D03*
X78600Y1561900D03*
X75000Y1561800D03*
X42199Y1601050D03*
X25521Y1563350D03*
X74800Y1584700D03*
X89373Y1561073D03*
X85600Y1561500D03*
X92873Y1708176D03*
X92479Y1718176D03*
X78100Y1688189D03*
X92900Y1678176D03*
X74500Y1692000D03*
X21600Y1702900D03*
X32700Y1673300D03*
X30274Y1787238D03*
X85599Y1797350D03*
X47899Y1798650D03*
X39000Y1750800D03*
X42275Y1754000D03*
X89306Y1746856D03*
X89499Y1753575D03*
X37699Y1789850D03*
X74400Y1778100D03*
X41200Y1747050D03*
X42199Y1792250D03*
X46799Y1794900D03*
X47400Y1765250D03*
X40478Y1795820D03*
X45877Y1728477D03*
Y1724823D03*
X47000Y1737100D03*
X43600D03*
X29599Y1844350D03*
X80099Y1817250D03*
X28123Y1831527D03*
X86649Y1817100D03*
X61009Y1822340D03*
X36532Y1825352D03*
X36399Y1828750D03*
X43099Y1833850D03*
X39699D03*
X40500Y1863000D03*
X22367Y1836633D03*
X50299Y1946650D03*
X53999D03*
X42532Y1946783D03*
X44399Y1942250D03*
X38703Y1946754D03*
X34799Y1946750D03*
X46565Y1946703D03*
X44368Y1951450D03*
X45999Y1971450D03*
X28799Y1919060D03*
X14999Y1940050D03*
X112999Y124050D03*
X111790Y132259D03*
X152499Y149550D03*
X173499Y149050D03*
X175999Y82428D03*
X97499Y90050D03*
X127999Y157050D03*
X114900Y177900D03*
X147099Y245350D03*
X124999Y246050D03*
X123300Y256000D03*
X157440Y283924D03*
Y303924D03*
Y313924D03*
X141499Y427550D03*
X166500Y428500D03*
X153459Y427494D03*
X154101Y445550D03*
X141499Y423050D03*
X159600Y446399D03*
X102100Y514900D03*
X163449Y521650D03*
X107526Y528996D03*
X104502Y530552D03*
X138999Y524213D03*
X173100Y483100D03*
X168453Y527949D03*
X160932Y549468D03*
X135499Y517550D03*
X107499Y497050D03*
X172499Y491053D03*
X109400Y543200D03*
X106000D03*
X138416Y553500D03*
X125499Y635550D03*
Y638950D03*
X144238Y645356D03*
X161000Y639100D03*
X124999Y643050D03*
X129000Y636600D03*
X128600Y640500D03*
X140900Y644000D03*
X134300Y646400D03*
X107000Y604800D03*
X105100Y600000D03*
X141300Y565900D03*
X144238Y649131D03*
X140400Y649800D03*
X158885Y679436D03*
Y689436D03*
X141500Y711000D03*
X158385Y719436D03*
X111200Y799450D03*
X110195Y809979D03*
X110500Y790200D03*
X110700Y795700D03*
X109831Y806598D03*
X109700Y803200D03*
X110202Y813379D03*
X154799Y838050D03*
X165499Y815550D03*
X110499Y834550D03*
X174199Y841050D03*
X169106Y815865D03*
X153900Y832200D03*
X106749Y934367D03*
X108441Y924705D03*
X160399Y922850D03*
X153499Y918550D03*
X171100Y935000D03*
X172000Y961000D03*
X152500Y960000D03*
X170250Y948500D03*
X171000Y939500D03*
X120100Y1053200D03*
X124100Y1047100D03*
X112699Y1058974D03*
X104600Y980500D03*
X103200Y985364D03*
X104700Y989900D03*
X120749Y1093990D03*
X106718Y1076050D03*
X137100Y1084800D03*
X121500Y1083600D03*
X121100Y1075300D03*
X116249Y1102550D03*
X112999Y1103740D03*
X117499Y1079300D03*
X157700Y1114948D03*
X157600Y1124948D03*
X159000Y1083000D03*
X127000Y1113500D03*
X123999Y1102550D03*
X116700Y1063500D03*
X105600Y1069500D03*
X137481Y1077557D03*
X137477Y1081177D03*
X124423Y1077523D03*
Y1081177D03*
X106162Y1205702D03*
X114999Y1210363D03*
X130699Y1210653D03*
X118999Y1219050D03*
X123970Y1221573D03*
X101500Y1352000D03*
X113500D03*
X113000Y1341000D03*
X102000D03*
X107228Y1330552D03*
X107500Y1340500D03*
X110499Y1365050D03*
X109999Y1355050D03*
X138000Y1359025D03*
X111499Y1311800D03*
X125999Y1315550D03*
X132999Y1319550D03*
X142667Y1319218D03*
X149562Y1315987D03*
X133475Y1331200D03*
X148024Y1333525D03*
X113500Y1344500D03*
Y1348154D03*
X139815Y1454438D03*
X139235Y1460973D03*
X123999Y1473050D03*
X127898Y1462441D03*
X107300Y1438100D03*
X114499Y1432050D03*
X114000Y1425400D03*
X107999Y1448050D03*
X150338Y1453958D03*
X152499Y1462940D03*
X105099Y1459150D03*
X157440Y1490460D03*
Y1500460D03*
Y1520460D03*
Y1530460D03*
X100499Y1479650D03*
X122199Y1476050D03*
X97499Y1554550D03*
X96999Y1558050D03*
X157400Y1596550D03*
X160200Y1598500D03*
X150999Y1713550D03*
X171999Y1662250D03*
X131999Y1710050D03*
X104999Y1708963D03*
X141500Y1715500D03*
X117249Y1712090D03*
X165575Y1676975D03*
X112753Y1716613D03*
X107300Y1746300D03*
X107100Y1736000D03*
X99199Y1761899D03*
X99999Y1753575D03*
X141999Y1764550D03*
X110099Y1759875D03*
X101399Y1784700D03*
X96600Y1826000D03*
X135999Y1881550D03*
X159421Y1925972D03*
X210638Y62959D03*
X210634Y66863D03*
X201499Y104550D03*
X245499Y100550D03*
X246499Y86050D03*
Y80550D03*
X215138Y72559D03*
X210685Y74725D03*
X210605Y70692D03*
X205938Y72528D03*
X210738Y78459D03*
Y82159D03*
X197899Y165075D03*
X225298Y281114D03*
X213499Y283864D03*
X213400Y355300D03*
X224998Y357049D03*
X233998Y357549D03*
X239400Y357400D03*
X252935Y319114D03*
X214063Y318114D03*
X231800Y318414D03*
X179700Y425800D03*
X199900Y554050D03*
X182499Y532550D03*
X220000Y516400D03*
X183499Y556100D03*
X188000Y484500D03*
X193549Y575875D03*
X216999Y686550D03*
X213999Y725050D03*
X230849Y726050D03*
X252499D03*
X228999Y765550D03*
X218224Y765325D03*
X241600Y765700D03*
X236800Y765800D03*
X199000Y815000D03*
X200539Y890300D03*
X198924Y975975D03*
X229562Y904113D03*
X215499Y905550D03*
X200799Y896600D03*
X233500Y1066100D03*
X226800Y1093400D03*
X256000Y1133000D03*
X255000Y1125700D03*
X221300Y1083238D03*
X182500Y1275500D03*
X232650Y1493450D03*
X179999Y1655887D03*
X186000Y1644000D03*
X194049Y1792600D03*
X227814Y1887513D03*
X236225Y1883125D03*
X232314Y1890513D03*
X213562Y1926113D03*
X220062Y1931113D03*
X240964Y1934113D03*
X257499Y1911050D03*
X343499Y60150D03*
X296099Y17100D03*
X305099Y17000D03*
X311400Y17100D03*
X317000Y17300D03*
X341499Y63050D03*
Y67110D03*
X291999Y94050D03*
X282800Y87500D03*
X297499Y97550D03*
X326499Y334054D03*
X284999Y338650D03*
X281499Y338550D03*
X313039Y352350D03*
X321900Y364600D03*
X298800Y333000D03*
X294500Y339000D03*
X326499Y337454D03*
X344520Y406329D03*
X308999Y716450D03*
X315999Y718950D03*
X279939Y728610D03*
X329499Y801550D03*
X330540Y795509D03*
X327999Y740550D03*
X320499Y798050D03*
X285499Y745050D03*
X282099D03*
X292999Y743650D03*
X298000Y743500D03*
X323249Y749010D03*
X324959Y766750D03*
X277039Y740300D03*
X327749Y744050D03*
X340699Y1046086D03*
X289999Y1554650D03*
X293700Y1553351D03*
X276039Y1551300D03*
X314999Y1527550D03*
X326500Y1550200D03*
X297800Y1561600D03*
X291400Y1561500D03*
X324000Y1562500D03*
X312999Y1566050D03*
X323999Y1577250D03*
X330300Y1561200D03*
X331622Y1944767D03*
X284999Y1947691D03*
X280689Y1942710D03*
X315999Y1958550D03*
X327100Y1966472D03*
X329999Y1952273D03*
X325221Y1927272D03*
X313499Y1919050D03*
X332103Y1948133D03*
X310499Y1957050D03*
X381999Y57050D03*
X398799Y36152D03*
X381999Y50150D03*
X386799Y45000D03*
X381999Y53550D03*
X426000Y93500D03*
X357503Y77043D03*
X374499Y77550D03*
X385999Y78050D03*
X401499Y80550D03*
X400499Y406329D03*
X371999Y549300D03*
X394649Y630600D03*
X375999Y698550D03*
X350499Y715050D03*
X371500Y880600D03*
X364499Y1099050D03*
X372999Y1123550D03*
X345499Y1096550D03*
X370149Y1320050D03*
X345424Y1310050D03*
X347324Y1524000D03*
X366149Y1554050D03*
X402499Y1476850D03*
X390999Y1514398D03*
Y1517798D03*
X349774Y1582900D03*
X354500Y1559500D03*
X400999Y1575550D03*
X354000Y1584900D03*
X353499Y1710450D03*
X377900Y1703800D03*
X348499Y1762050D03*
X385499Y1735050D03*
X367000Y1810000D03*
X360000Y1967500D03*
X659549Y1810634D03*
X757499Y745342D03*
X755600Y1149800D03*
X758499Y1371050D03*
X754000Y1551000D03*
X690249Y1805634D03*
X755000Y1825000D03*
X752500Y1954500D03*
X821999Y193116D03*
X827499Y163550D03*
X820749Y163850D03*
X813249Y163800D03*
X839249Y164050D03*
X837999Y219550D03*
X770999Y302050D03*
X785499Y291050D03*
X770999Y290050D03*
Y295550D03*
X827499Y313424D03*
X763571Y295622D03*
X777999Y296050D03*
X786978Y298529D03*
X836500Y274950D03*
X812500Y282750D03*
X789999Y336550D03*
X758778Y345000D03*
X768178Y333964D03*
X784499Y334050D03*
X772873Y326924D03*
X780499Y330050D03*
X835150Y677650D03*
X806500Y687250D03*
X781999Y725550D03*
X788999Y736050D03*
X766499Y732842D03*
X762500Y734000D03*
X784939Y733550D03*
X769999Y733050D03*
X767083Y1134550D03*
X764549Y1138500D03*
X784439Y1136550D03*
X814000Y1087000D03*
X772499Y1130050D03*
X789499Y1138050D03*
X779499Y1131050D03*
X836625Y1487400D03*
X771225Y1539474D03*
X767936Y1540336D03*
X784577Y1535628D03*
X812550Y1494050D03*
X774577Y1533796D03*
X791499Y1543550D03*
X788000Y1788000D03*
X774500D03*
X812000Y1799500D03*
X821249Y1791250D03*
X811000Y1793000D03*
X770999Y1820550D03*
X822499Y1815164D03*
X791999Y1819050D03*
X783499Y1827050D03*
X767999Y1945173D03*
X764908Y1946592D03*
X785939Y1946800D03*
X812500Y1898500D03*
X771499Y1940050D03*
X792499Y1949050D03*
X919800Y54600D03*
X924200Y69800D03*
X898800Y96000D03*
X855500Y149500D03*
X873000Y148500D03*
X846500Y149500D03*
X841499Y135550D03*
X861999Y146550D03*
X882499Y147050D03*
X896999Y141550D03*
X916499Y115050D03*
X923761Y85550D03*
X854400Y264600D03*
X847500Y246600D03*
X850999Y246550D03*
X874700Y244900D03*
X874900Y238600D03*
X871999Y283924D03*
X886200Y313924D03*
X886600Y303924D03*
X872136Y273924D03*
X858478Y274050D03*
X902999Y556050D03*
X875100Y644400D03*
X922049Y574375D03*
X875300Y650500D03*
X851300Y651700D03*
X847600Y651600D03*
X852696Y671197D03*
X922049Y978575D03*
X900499Y962100D03*
X847500Y1057800D03*
X851000Y1058000D03*
X874733Y1055792D03*
X874999Y1049550D03*
X852333Y1077716D03*
X871499Y1124948D03*
X872086Y1114948D03*
X871999Y1094948D03*
X872086Y1084948D03*
X860133Y1084142D03*
X860799Y1358925D03*
X874100Y1461600D03*
X874900Y1454000D03*
X848861Y1462463D03*
X852500Y1462600D03*
X854327Y1477550D03*
X858827Y1485696D03*
X872086Y1490460D03*
X871999Y1500460D03*
Y1520460D03*
X872086Y1530460D03*
X900500Y1721500D03*
X921549Y1788475D03*
X851500Y1821400D03*
X849375Y1824982D03*
X854905Y1825583D03*
X854480Y1867578D03*
X849999Y1867550D03*
X863700Y1867300D03*
X865300Y1858700D03*
X854814Y1883550D03*
X859314Y1891365D03*
X871921Y1905972D03*
X871421Y1895972D03*
X872086Y1925972D03*
Y1935972D03*
X961499Y100050D03*
X946899Y122550D03*
X932961Y85581D03*
X928461Y75981D03*
X928561Y91481D03*
X928508Y87747D03*
X928428Y83714D03*
X928561Y95181D03*
X928457Y79885D03*
X958999Y96050D03*
X939549Y175175D03*
X966499Y552050D03*
X965999Y954550D03*
X990425Y1633898D03*
X987029Y1634075D03*
X981200Y1618002D03*
X969600Y1638300D03*
X967600Y1651100D03*
X989502Y1646000D03*
X988800Y1658300D03*
X989000Y1663802D03*
X987200Y1675600D03*
X989900Y1678800D03*
X971558Y1646500D03*
G54D12*
X17720Y1903144D03*
X29532Y309561D03*
X271657Y267711D03*
Y673223D03*
Y1078734D03*
Y1484246D03*
Y1889758D03*
X994098Y149601D03*
Y673223D03*
X994099Y1068892D03*
G54D13*
X68898Y17047D03*
Y190275D03*
Y422559D03*
Y595787D03*
Y828071D03*
Y1001299D03*
Y1233583D03*
Y1406811D03*
Y1639095D03*
Y1812323D03*
X167323Y179803D03*
Y353031D03*
Y585315D03*
Y758543D03*
Y990827D03*
Y1164055D03*
Y1396339D03*
Y1569567D03*
Y1801851D03*
Y1975079D03*
X895669Y179803D03*
Y353031D03*
Y585315D03*
Y758543D03*
Y990827D03*
Y1164055D03*
Y1396339D03*
Y1569567D03*
Y1801851D03*
Y1975079D03*
G54D14*
X129920Y17716D03*
X994093Y1889751D03*
G54D15*
G01X-71137Y-139897D02*
Y-219897D01*
G01D02*
X1129963D01*
G01X-75137Y-123897D02*
G02I-12000J0D01*
G01X-80287D02*
G02I-6850J0D01*
G01X-87137Y-139897D02*
Y-107897D01*
G01X-71137Y-123897D02*
X-103137D01*
G01X-71137Y-139897D02*
X1129963D01*
G01X-71137Y-175397D02*
X1129963D01*
G01X8750Y1086250D02*
X23750D01*
X26500Y1089000D01*
Y1129500D01*
X21817Y1134183D01*
Y1156317D01*
G01X141300Y565900D02*
X142900D01*
X145499Y568499D01*
Y598525D01*
X154999Y608025D01*
Y641595D01*
X155300Y641896D01*
Y652794D01*
X153326Y654768D01*
X127868D01*
X81251Y608151D01*
Y607249D01*
G01Y619251D02*
X86451D01*
X125168Y657968D01*
X154652D01*
X158500Y654120D01*
Y640570D01*
X158199Y640269D01*
Y606699D01*
X148699Y597199D01*
Y562900D01*
X139299Y553500D01*
X138416D01*
G01X40500Y1863000D02*
X38137D01*
X22367Y1847230D01*
Y1836633D01*
G01X104600Y980500D02*
X111500D01*
X141200Y950800D01*
X154503D01*
X159186Y946117D01*
G01X103200Y985364D02*
X114162D01*
X145526Y954000D01*
X163021D01*
X168521Y948500D01*
X170250D01*
G01X104700Y989900D02*
X114152D01*
X146852Y957200D01*
X164347D01*
X168097Y953450D01*
X169826D01*
X173450Y949826D01*
Y947150D01*
X171000Y944700D01*
Y939500D01*
G01X233500Y1066100D02*
Y1086700D01*
X226800Y1093400D01*
G01X342463Y-139897D02*
Y-219897D01*
G01X479963Y-139897D02*
Y-219897D01*
G01X594963Y-139897D02*
Y-219897D01*
G01X767159Y1792364D02*
X759345Y1784550D01*
X637999D01*
X633837Y1788712D01*
Y1807384D01*
G01X762463Y-139897D02*
Y-219897D01*
G01X932463Y-139897D02*
Y-219897D01*
G01X1129963Y-139897D02*
Y-219897D01*
G01X1157963Y-123897D02*
G02I-12000J0D01*
G01X1152813D02*
G02I-6850J0D01*
G01X1145963Y-139897D02*
Y-107897D01*
G01X1161963Y-123897D02*
X1129963D01*
G54D16*
G01X161999Y768050D02*
X51499Y657550D01*
X43499D01*
G01X148024Y1333525D02*
X167999Y1313550D01*
X168062D01*
X175499Y1306113D01*
G54D17*
G01X8518Y1903144D02*
X17720D01*
G01X68898Y12645D02*
Y17047D01*
G01D02*
Y21449D01*
G01X62346Y17047D02*
X68898D01*
G01D02*
X75450D01*
G01X68898Y185873D02*
Y190275D01*
G01D02*
Y194677D01*
G01X62346Y190275D02*
X68898D01*
G01D02*
X75450D01*
G01X29532Y300359D02*
Y309561D01*
G01D02*
Y318763D01*
G01X20330Y309561D02*
X29532D01*
G01D02*
X38734D01*
G01X68898Y422559D02*
Y426961D01*
G01X62346D02*
X68898Y422559D01*
G01Y591385D02*
Y595787D01*
G01D02*
Y600189D01*
G01X62346Y595787D02*
X68898D01*
G01D02*
X75450D01*
G01X68898Y823669D02*
Y828071D01*
G01D02*
Y832473D01*
G01Y828071D02*
X75450D01*
G01X68898Y996897D02*
Y1001299D01*
G01D02*
Y1005701D01*
G01Y1001299D02*
X75450D01*
G01X68898Y1229181D02*
Y1233583D01*
G01D02*
Y1237985D01*
G01X62346Y1233583D02*
X68898D01*
G01D02*
X75450D01*
G01X68898Y1402409D02*
Y1406811D01*
G01D02*
Y1411213D01*
G01Y1406811D02*
X75450D01*
G01X68898Y1634693D02*
Y1639095D01*
G01D02*
Y1643497D01*
G01Y1639095D02*
X75450D01*
G01X68898Y1807921D02*
Y1812323D01*
G01X62346D02*
X68898D01*
G01X17720Y1893942D02*
Y1903144D01*
G01D02*
Y1912346D01*
G01Y1903144D02*
X26922D01*
G01X129920Y7664D02*
Y17716D01*
G01X119868D02*
X129920D01*
G01D02*
X139972D01*
G01X167323Y175401D02*
Y179803D01*
G01D02*
Y184205D01*
G01X160771Y179803D02*
X167323D01*
G01D02*
X173875D01*
G01X167323Y348629D02*
Y353031D01*
G01D02*
Y357433D01*
G01X160771Y353031D02*
X167323D01*
G01D02*
X173875D01*
G01X167323Y580913D02*
Y585315D01*
G01D02*
Y589717D01*
G01Y585315D02*
X173875D01*
G01X167323Y754141D02*
Y758543D01*
G01D02*
Y762945D01*
G01X160771Y758543D02*
X167323D01*
G01D02*
X173875D01*
G01X167323Y986425D02*
Y990827D01*
G01D02*
Y995229D01*
G01X160771Y990827D02*
X167323D01*
G01D02*
X173875D01*
G01X167323Y1159653D02*
Y1164055D01*
G01D02*
Y1168457D01*
G01X160771Y1164055D02*
X167323D01*
G01D02*
X173875D01*
G01X167323Y1391937D02*
Y1396339D01*
G01D02*
Y1400741D01*
G01X160771Y1396339D02*
X167323D01*
G01D02*
X173875D01*
G01X167323Y1565165D02*
Y1569567D01*
G01D02*
Y1573969D01*
G01X160771Y1569567D02*
X167323D01*
G01D02*
X173875D01*
G01X167323Y1797449D02*
Y1801851D01*
G01D02*
Y1806253D01*
G01X160771Y1801851D02*
X167323D01*
G01D02*
X173875D01*
G01X167323Y1970677D02*
Y1975079D01*
G01D02*
Y1979481D01*
G01X160771Y1975079D02*
X167323D01*
G01D02*
X173875D01*
G01X271657Y258509D02*
Y267711D01*
G01D02*
Y276913D01*
G01X262455Y267711D02*
X271657D01*
G01D02*
X280859D01*
G01X271657Y664021D02*
Y673223D01*
G01D02*
Y682425D01*
G01X262455Y673223D02*
X271657D01*
G01D02*
X280859D01*
G01X271657Y1069532D02*
Y1078734D01*
G01D02*
Y1087936D01*
G01X262455Y1078734D02*
X271657D01*
G01D02*
X280859D01*
G01X271657Y1475044D02*
Y1484246D01*
G01D02*
Y1493448D01*
G01X262455Y1484246D02*
X271657D01*
G01D02*
X280859D01*
G01X271657Y1880556D02*
Y1889758D01*
G01D02*
Y1898960D01*
G01X262455Y1889758D02*
X271657D01*
G01D02*
X280859D01*
G01X895669Y175401D02*
Y179803D01*
G01D02*
Y184205D01*
G01X889117Y179803D02*
X895669D01*
G01D02*
X902221D01*
G01X895669Y348629D02*
Y353031D01*
G01D02*
Y357433D01*
G01X889117Y353031D02*
X895669D01*
G01D02*
X902221D01*
G01X895669Y580913D02*
Y585315D01*
G01D02*
Y589717D01*
G01X889117Y585315D02*
X895669D01*
G01D02*
X902221D01*
G01X895669Y754141D02*
Y758543D01*
G01D02*
Y762945D01*
G01X889117Y758543D02*
X895669D01*
G01D02*
X902221D01*
G01X895669Y986425D02*
Y990827D01*
G01D02*
Y995229D01*
G01X889117Y990827D02*
X895669D01*
G01Y1159653D02*
Y1164055D01*
G01D02*
Y1168457D01*
G01X889117Y1164055D02*
X895669D01*
G01Y1391937D02*
Y1396339D01*
G01D02*
Y1400741D01*
G01X889117Y1396339D02*
X895669D01*
G01Y1565165D02*
Y1569567D01*
G01D02*
Y1573969D01*
G01X889117Y1569567D02*
X895669D01*
G01D02*
X902221D01*
G01X895669Y1797449D02*
Y1801851D01*
G01D02*
Y1806253D01*
G01X889117Y1801851D02*
X895669D01*
G01D02*
X902221D01*
G01X895669Y1970677D02*
Y1975079D01*
G01D02*
Y1979481D01*
G01X889117Y1975079D02*
X895669D01*
G01D02*
X902221D01*
G01X994098Y140399D02*
Y149601D01*
G01D02*
Y158803D01*
G01X984896Y149601D02*
X994098D01*
G01D02*
X1003300D01*
G01X994098Y664021D02*
Y673223D01*
G01D02*
Y682425D01*
G01X984896Y673223D02*
X994098D01*
G01D02*
X1003300D01*
G01X994099Y1059690D02*
Y1068892D01*
G01D02*
Y1078094D01*
G01X984897Y1068892D02*
X994099D01*
G01D02*
X1003301D01*
G01X994093Y1879699D02*
Y1889751D01*
G01D02*
Y1899803D01*
G01X984041Y1889751D02*
X994093D01*
G01D02*
X1004145D01*
G54D18*
G01X-89222Y-207897D02*
Y-190397D01*
G01X-80052D02*
Y-207897D01*
G01Y-199147D02*
X-89222D01*
G01X-67137Y-207897D02*
X-68447Y-207605D01*
X-69757Y-206439D01*
X-70631Y-204397D01*
X-71067Y-202064D01*
X-70631Y-199730D01*
X-69757Y-197689D01*
X-68447Y-196522D01*
X-67137Y-196231D01*
X-65827Y-196522D01*
X-64517Y-197689D01*
X-63644Y-199730D01*
X-63425Y-202064D01*
X-63644Y-204397D01*
X-64517Y-206439D01*
X-65827Y-207605D01*
X-67137Y-207897D01*
G01X-53349D02*
Y-196231D01*
G01Y-199147D02*
X-52475Y-197689D01*
X-51165Y-196522D01*
X-49419Y-196231D01*
X-47891Y-196522D01*
X-46580Y-197689D01*
X-45925Y-199730D01*
Y-207897D01*
G01X-35412Y-200022D02*
X-28425D01*
X-29080Y-197980D01*
X-30172Y-196814D01*
X-31700Y-196231D01*
X-33229Y-196522D01*
X-34539Y-197397D01*
X-35412Y-199439D01*
X-35849Y-201189D01*
Y-202939D01*
X-35412Y-204689D01*
X-34320Y-206439D01*
X-33010Y-207605D01*
X-31482Y-207897D01*
X-29954Y-207314D01*
X-28425Y-205564D01*
G01X-19222Y-213147D02*
X-17912Y-213730D01*
X-16165Y-213147D01*
X-15074Y-211981D01*
X-14200Y-210522D01*
X-12891Y-205856D01*
X-10052Y-196231D01*
G01X-17039D02*
X-12891Y-205856D01*
G01X22109Y-198564D02*
X22983Y-197689D01*
X23638Y-196231D01*
X24075Y-194188D01*
X23638Y-192439D01*
X22765Y-191272D01*
X21236Y-190397D01*
X15341D01*
Y-207897D01*
X22546D01*
X24075Y-206731D01*
X24948Y-204980D01*
X25385Y-202939D01*
X24948Y-200897D01*
X23638Y-199147D01*
X22109Y-198564D01*
X15341D01*
G01X41793Y-207897D02*
Y-196231D01*
G01Y-198272D02*
X40920Y-197106D01*
X39609Y-196522D01*
X38081Y-196231D01*
X36553Y-196814D01*
X35243Y-197980D01*
X34369Y-199730D01*
X33933Y-202064D01*
X34369Y-204397D01*
X35243Y-206147D01*
X36553Y-207314D01*
X38081Y-207897D01*
X39609Y-207605D01*
X40920Y-206731D01*
X41793Y-205564D01*
G01X59293Y-190397D02*
Y-207897D01*
G01Y-205273D02*
X58420Y-206731D01*
X57109Y-207605D01*
X55581Y-207897D01*
X53835Y-207314D01*
X52525Y-205856D01*
X51651Y-204106D01*
X51433Y-202064D01*
X51651Y-200022D01*
X52525Y-198272D01*
X53835Y-196814D01*
X55581Y-196231D01*
X57109Y-196522D01*
X58201Y-197106D01*
X59293Y-198272D01*
G01X69806Y-212272D02*
X71335Y-213439D01*
X73081Y-213730D01*
X74609Y-213439D01*
X75920Y-211981D01*
X76793Y-209939D01*
Y-196231D01*
G01Y-198564D02*
X75920Y-197397D01*
X74609Y-196522D01*
X73081Y-196231D01*
X71335Y-196814D01*
X70243Y-197980D01*
X69369Y-200022D01*
X68933Y-202064D01*
X69151Y-203814D01*
X70025Y-205856D01*
X71335Y-207314D01*
X73081Y-207897D01*
X74391Y-207605D01*
X75920Y-206439D01*
X76793Y-205273D01*
G01X87088Y-200022D02*
X94075D01*
X93420Y-197980D01*
X92328Y-196814D01*
X90800Y-196231D01*
X89271Y-196522D01*
X87961Y-197397D01*
X87088Y-199439D01*
X86651Y-201189D01*
Y-202939D01*
X87088Y-204689D01*
X88180Y-206439D01*
X89490Y-207605D01*
X91018Y-207897D01*
X92546Y-207314D01*
X94075Y-205564D01*
G01X104806Y-207897D02*
Y-196231D01*
G01Y-198564D02*
X105898Y-197397D01*
X106990Y-196522D01*
X108518Y-196231D01*
X109609Y-196522D01*
X110920Y-197397D01*
G01X138060Y-207897D02*
Y-190397D01*
X142426D01*
X144173Y-191272D01*
X145483Y-192439D01*
X146575Y-194188D01*
X147448Y-196231D01*
X147666Y-199147D01*
X147448Y-202064D01*
X146575Y-204106D01*
X145483Y-205856D01*
X144173Y-207022D01*
X142426Y-207897D01*
X138060D01*
G01X155996D02*
Y-190397D01*
X161236D01*
X162983Y-191272D01*
X164293Y-193314D01*
X164730Y-195647D01*
X164293Y-197980D01*
X163201Y-199730D01*
X161236Y-200606D01*
X155996D01*
G01X179609Y-198564D02*
X180483Y-197689D01*
X181138Y-196231D01*
X181575Y-194188D01*
X181138Y-192439D01*
X180265Y-191272D01*
X178736Y-190397D01*
X172841D01*
Y-207897D01*
X180046D01*
X181575Y-206731D01*
X182448Y-204980D01*
X182885Y-202939D01*
X182448Y-200897D01*
X181138Y-199147D01*
X179609Y-198564D01*
X172841D01*
G01X208496Y-190397D02*
Y-207897D01*
X217230D01*
G01X230363D02*
X229053Y-207605D01*
X227743Y-206439D01*
X226869Y-204397D01*
X226433Y-202064D01*
X226869Y-199730D01*
X227743Y-197689D01*
X229053Y-196522D01*
X230363Y-196231D01*
X231673Y-196522D01*
X232983Y-197689D01*
X233856Y-199730D01*
X234075Y-202064D01*
X233856Y-204397D01*
X232983Y-206439D01*
X231673Y-207605D01*
X230363Y-207897D01*
G01X242404Y-196231D02*
X245025Y-207897D01*
X247863Y-196231D01*
X250701Y-207897D01*
X253322Y-196231D01*
G01X278496Y-190397D02*
Y-207897D01*
X287230D01*
G01X300363D02*
X299053Y-207605D01*
X297743Y-206439D01*
X296869Y-204397D01*
X296433Y-202064D01*
X296869Y-199730D01*
X297743Y-197689D01*
X299053Y-196522D01*
X300363Y-196231D01*
X301673Y-196522D01*
X302983Y-197689D01*
X303856Y-199730D01*
X304075Y-202064D01*
X303856Y-204397D01*
X302983Y-206439D01*
X301673Y-207605D01*
X300363Y-207897D01*
G01X314588Y-205856D02*
X315680Y-207022D01*
X317208Y-207897D01*
X318518D01*
X319828Y-207314D01*
X320701Y-206439D01*
X321138Y-205273D01*
X320920Y-203522D01*
X320046Y-202647D01*
X316116Y-200897D01*
X315243Y-198855D01*
X315680Y-197397D01*
X316553Y-196522D01*
X317863Y-196231D01*
X319173Y-196522D01*
X320483Y-197397D01*
G01X332088Y-205856D02*
X333180Y-207022D01*
X334708Y-207897D01*
X336018D01*
X337328Y-207314D01*
X338201Y-206439D01*
X338638Y-205273D01*
X338420Y-203522D01*
X337546Y-202647D01*
X333616Y-200897D01*
X332743Y-198855D01*
X333180Y-197397D01*
X334053Y-196522D01*
X335363Y-196231D01*
X336673Y-196522D01*
X337983Y-197397D01*
G01X94686Y-164897D02*
Y-147397D01*
X100363Y-161980D01*
X106040Y-147397D01*
Y-164897D01*
G01X117863D02*
X116553Y-164605D01*
X115243Y-163439D01*
X114369Y-161397D01*
X113933Y-159064D01*
X114369Y-156730D01*
X115243Y-154689D01*
X116553Y-153522D01*
X117863Y-153231D01*
X119173Y-153522D01*
X120483Y-154689D01*
X121356Y-156730D01*
X121575Y-159064D01*
X121356Y-161397D01*
X120483Y-163439D01*
X119173Y-164605D01*
X117863Y-164897D01*
G01X139293Y-147397D02*
Y-164897D01*
G01Y-162273D02*
X138420Y-163731D01*
X137109Y-164605D01*
X135581Y-164897D01*
X133835Y-164314D01*
X132525Y-162856D01*
X131651Y-161106D01*
X131433Y-159064D01*
X131651Y-157022D01*
X132525Y-155272D01*
X133835Y-153814D01*
X135581Y-153231D01*
X137109Y-153522D01*
X138201Y-154106D01*
X139293Y-155272D01*
G01X149588Y-157022D02*
X156575D01*
X155920Y-154980D01*
X154828Y-153814D01*
X153300Y-153231D01*
X151771Y-153522D01*
X150461Y-154397D01*
X149588Y-156439D01*
X149151Y-158189D01*
Y-159939D01*
X149588Y-161689D01*
X150680Y-163439D01*
X151990Y-164605D01*
X153518Y-164897D01*
X155046Y-164314D01*
X156575Y-162564D01*
G01X170363Y-164897D02*
Y-147397D01*
G01X376163Y-209897D02*
Y-192397D01*
X373543Y-195897D01*
G01Y-209897D02*
X378783D01*
G01X396283D02*
Y-192397D01*
X388204Y-204939D01*
X399122D01*
G01X406360Y-207273D02*
X407669Y-208731D01*
X409198Y-209605D01*
X411163Y-209897D01*
X413128Y-209314D01*
X414656Y-208147D01*
X415748Y-206106D01*
X415966Y-203772D01*
X415530Y-201439D01*
X414438Y-199980D01*
X412909Y-198814D01*
X411381Y-198522D01*
X409853Y-198814D01*
X407888Y-199980D01*
X408543Y-192397D01*
X414438D01*
G01X431283Y-209897D02*
Y-192397D01*
X423204Y-204939D01*
X434122D01*
G01X441360Y-207273D02*
X442669Y-208731D01*
X444198Y-209605D01*
X446163Y-209897D01*
X448128Y-209314D01*
X449656Y-208147D01*
X450748Y-206106D01*
X450966Y-203772D01*
X450530Y-201439D01*
X449438Y-199980D01*
X447909Y-198814D01*
X446381Y-198522D01*
X444853Y-198814D01*
X442888Y-199980D01*
X443543Y-192397D01*
X449438D01*
G01X363046Y-164897D02*
Y-147397D01*
X368286D01*
X370033Y-148272D01*
X371343Y-150314D01*
X371780Y-152647D01*
X371343Y-154980D01*
X370251Y-156730D01*
X368286Y-157606D01*
X363046D01*
G01X389716Y-148856D02*
X388406Y-147980D01*
X386878Y-147397D01*
X385131D01*
X383166Y-148272D01*
X381638Y-149730D01*
X380546Y-151481D01*
X379673Y-154397D01*
X379454Y-157022D01*
X379891Y-159647D01*
X380546Y-161397D01*
X381856Y-163147D01*
X383385Y-164314D01*
X384913Y-164897D01*
X386441D01*
X387970Y-164314D01*
X389280Y-163439D01*
X390372Y-162273D01*
G01X404159Y-155564D02*
X405033Y-154689D01*
X405688Y-153231D01*
X406125Y-151188D01*
X405688Y-149439D01*
X404815Y-148272D01*
X403286Y-147397D01*
X397391D01*
Y-164897D01*
X404596D01*
X406125Y-163731D01*
X406998Y-161980D01*
X407435Y-159939D01*
X406998Y-157897D01*
X405688Y-156147D01*
X404159Y-155564D01*
X397391D01*
G01X413363Y-170730D02*
X426463D01*
G01X432391Y-164897D02*
Y-147397D01*
X442435Y-164897D01*
Y-147397D01*
G01X454913Y-164897D02*
X453166Y-164605D01*
X451638Y-163439D01*
X450328Y-161689D01*
X449454Y-159647D01*
X449018Y-157314D01*
Y-154980D01*
X449454Y-152647D01*
X450328Y-150605D01*
X451638Y-148856D01*
X453166Y-147689D01*
X454913Y-147397D01*
X456659Y-147689D01*
X458188Y-148856D01*
X459498Y-150605D01*
X460372Y-152647D01*
X460808Y-154980D01*
Y-157314D01*
X460372Y-159647D01*
X459498Y-161689D01*
X458188Y-163439D01*
X456659Y-164605D01*
X454913Y-164897D01*
G01X505754Y-147397D02*
X511213Y-164897D01*
X516672Y-147397D01*
G01X533080Y-164897D02*
X524346D01*
Y-147397D01*
X533080D01*
G01X529586Y-155855D02*
X524346D01*
G01X541846Y-164897D02*
Y-147397D01*
X547305D01*
X549051Y-148272D01*
X550143Y-149439D01*
X550580Y-151772D01*
X550143Y-154106D01*
X548833Y-155564D01*
X547305Y-156439D01*
X541846D01*
G01X547305D02*
X550580Y-164897D01*
G01X563713Y-165480D02*
X563276Y-165189D01*
Y-164605D01*
X563713Y-164314D01*
X564150Y-164605D01*
Y-165189D01*
X563713Y-165480D01*
G01X524128Y-207564D02*
X525875Y-209022D01*
X527840Y-209897D01*
X529586D01*
X531333Y-209022D01*
X532643Y-207564D01*
X533298Y-205522D01*
X532861Y-203481D01*
X531770Y-201730D01*
X529805Y-200564D01*
X527185Y-199980D01*
X525656Y-198814D01*
X525001Y-196772D01*
X525438Y-194730D01*
X526530Y-193272D01*
X528058Y-192397D01*
X529586D01*
X531115Y-192980D01*
X532425Y-194439D01*
G01X540754Y-209897D02*
X546213Y-192397D01*
X551672Y-209897D01*
G01X549706Y-203772D02*
X542719D01*
G01X691780Y-192397D02*
Y-209897D01*
X683046D01*
G01X674061Y-202606D02*
X672533Y-200564D01*
X671223Y-199397D01*
X669476Y-198814D01*
X667948Y-199397D01*
X666856Y-200564D01*
X665983Y-202314D01*
X665765Y-204355D01*
X665983Y-206106D01*
X666856Y-207856D01*
X668167Y-209314D01*
X669695Y-209897D01*
X671441Y-209314D01*
X672970Y-207564D01*
X673843Y-204939D01*
X674061Y-202022D01*
X673625Y-198231D01*
X672970Y-196188D01*
X671878Y-194147D01*
X670350Y-192689D01*
X668821Y-192397D01*
X667293Y-192980D01*
X666201Y-194439D01*
G01X630546Y-147397D02*
Y-164897D01*
X639280D01*
G01X656343D02*
Y-153231D01*
G01Y-155272D02*
X655470Y-154106D01*
X654159Y-153522D01*
X652631Y-153231D01*
X651103Y-153814D01*
X649793Y-154980D01*
X648919Y-156730D01*
X648483Y-159064D01*
X648919Y-161397D01*
X649793Y-163147D01*
X651103Y-164314D01*
X652631Y-164897D01*
X654159Y-164605D01*
X655470Y-163731D01*
X656343Y-162564D01*
G01X665328Y-170147D02*
X666638Y-170730D01*
X668385Y-170147D01*
X669476Y-168981D01*
X670350Y-167522D01*
X671659Y-162856D01*
X674498Y-153231D01*
G01X667511D02*
X671659Y-162856D01*
G01X684138Y-157022D02*
X691125D01*
X690470Y-154980D01*
X689378Y-153814D01*
X687850Y-153231D01*
X686321Y-153522D01*
X685011Y-154397D01*
X684138Y-156439D01*
X683701Y-158189D01*
Y-159939D01*
X684138Y-161689D01*
X685230Y-163439D01*
X686540Y-164605D01*
X688068Y-164897D01*
X689596Y-164314D01*
X691125Y-162564D01*
G01X701856Y-164897D02*
Y-153231D01*
G01Y-155564D02*
X702948Y-154397D01*
X704040Y-153522D01*
X705568Y-153231D01*
X706659Y-153522D01*
X707970Y-154397D01*
G01X719138Y-162856D02*
X720230Y-164022D01*
X721758Y-164897D01*
X723068D01*
X724378Y-164314D01*
X725251Y-163439D01*
X725688Y-162273D01*
X725470Y-160522D01*
X724596Y-159647D01*
X720666Y-157897D01*
X719793Y-155855D01*
X720230Y-154397D01*
X721103Y-153522D01*
X722413Y-153231D01*
X723723Y-153522D01*
X725033Y-154397D01*
G01X790596Y-209897D02*
Y-192397D01*
X796055D01*
X797801Y-193272D01*
X798893Y-194439D01*
X799330Y-196772D01*
X798893Y-199106D01*
X797583Y-200564D01*
X796055Y-201439D01*
X790596D01*
G01X796055D02*
X799330Y-209897D01*
G01X809188Y-202022D02*
X816175D01*
X815520Y-199980D01*
X814428Y-198814D01*
X812900Y-198231D01*
X811371Y-198522D01*
X810061Y-199397D01*
X809188Y-201439D01*
X808751Y-203189D01*
Y-204939D01*
X809188Y-206689D01*
X810280Y-208439D01*
X811590Y-209605D01*
X813118Y-209897D01*
X814646Y-209314D01*
X816175Y-207564D01*
G01X826033Y-209897D02*
Y-192397D01*
G01Y-201147D02*
X827125Y-199397D01*
X828435Y-198522D01*
X829745Y-198231D01*
X831709Y-198814D01*
X833020Y-199980D01*
X833893Y-202022D01*
Y-204355D01*
X833456Y-206689D01*
X832583Y-208439D01*
X831055Y-209605D01*
X829745Y-209897D01*
X828435Y-209605D01*
X827125Y-208731D01*
X826033Y-207273D01*
G01X844188Y-202022D02*
X851175D01*
X850520Y-199980D01*
X849428Y-198814D01*
X847900Y-198231D01*
X846371Y-198522D01*
X845061Y-199397D01*
X844188Y-201439D01*
X843751Y-203189D01*
Y-204939D01*
X844188Y-206689D01*
X845280Y-208439D01*
X846590Y-209605D01*
X848118Y-209897D01*
X849646Y-209314D01*
X851175Y-207564D01*
G01X868456Y-199689D02*
X866928Y-198522D01*
X865618Y-198231D01*
X863871Y-198814D01*
X862561Y-199980D01*
X861688Y-202022D01*
X861469Y-204064D01*
X861688Y-206106D01*
X862561Y-207856D01*
X863871Y-209314D01*
X865618Y-209897D01*
X867146Y-209314D01*
X868456Y-208147D01*
G01X885956Y-199689D02*
X884428Y-198522D01*
X883118Y-198231D01*
X881371Y-198814D01*
X880061Y-199980D01*
X879188Y-202022D01*
X878969Y-204064D01*
X879188Y-206106D01*
X880061Y-207856D01*
X881371Y-209314D01*
X883118Y-209897D01*
X884646Y-209314D01*
X885956Y-208147D01*
G01X903893Y-209897D02*
Y-198231D01*
G01Y-200272D02*
X903020Y-199106D01*
X901709Y-198522D01*
X900181Y-198231D01*
X898653Y-198814D01*
X897343Y-199980D01*
X896469Y-201730D01*
X896033Y-204064D01*
X896469Y-206397D01*
X897343Y-208147D01*
X898653Y-209314D01*
X900181Y-209897D01*
X901709Y-209605D01*
X903020Y-208731D01*
X903893Y-207564D01*
G01X781410Y-164897D02*
Y-147397D01*
X785776D01*
X787523Y-148272D01*
X788833Y-149439D01*
X789925Y-151188D01*
X790798Y-153231D01*
X791016Y-156147D01*
X790798Y-159064D01*
X789925Y-161106D01*
X788833Y-162856D01*
X787523Y-164022D01*
X785776Y-164897D01*
X781410D01*
G01X800438Y-157022D02*
X807425D01*
X806770Y-154980D01*
X805678Y-153814D01*
X804150Y-153231D01*
X802621Y-153522D01*
X801311Y-154397D01*
X800438Y-156439D01*
X800001Y-158189D01*
Y-159939D01*
X800438Y-161689D01*
X801530Y-163439D01*
X802840Y-164605D01*
X804368Y-164897D01*
X805896Y-164314D01*
X807425Y-162564D01*
G01X817938Y-162856D02*
X819030Y-164022D01*
X820558Y-164897D01*
X821868D01*
X823178Y-164314D01*
X824051Y-163439D01*
X824488Y-162273D01*
X824270Y-160522D01*
X823396Y-159647D01*
X819466Y-157897D01*
X818593Y-155855D01*
X819030Y-154397D01*
X819903Y-153522D01*
X821213Y-153231D01*
X822523Y-153522D01*
X823833Y-154397D01*
G01X838713Y-153231D02*
Y-164897D01*
G01Y-148564D02*
X838276Y-148272D01*
Y-147689D01*
X838713Y-147397D01*
X839150Y-147689D01*
Y-148272D01*
X838713Y-148564D01*
G01X853156Y-169272D02*
X854685Y-170439D01*
X856431Y-170730D01*
X857959Y-170439D01*
X859270Y-168981D01*
X860143Y-166939D01*
Y-153231D01*
G01Y-155564D02*
X859270Y-154397D01*
X857959Y-153522D01*
X856431Y-153231D01*
X854685Y-153814D01*
X853593Y-154980D01*
X852719Y-157022D01*
X852283Y-159064D01*
X852501Y-160814D01*
X853375Y-162856D01*
X854685Y-164314D01*
X856431Y-164897D01*
X857741Y-164605D01*
X859270Y-163439D01*
X860143Y-162273D01*
G01X870001Y-164897D02*
Y-153231D01*
G01Y-156147D02*
X870875Y-154689D01*
X872185Y-153522D01*
X873931Y-153231D01*
X875459Y-153522D01*
X876770Y-154689D01*
X877425Y-156730D01*
Y-164897D01*
G01X887938Y-157022D02*
X894925D01*
X894270Y-154980D01*
X893178Y-153814D01*
X891650Y-153231D01*
X890121Y-153522D01*
X888811Y-154397D01*
X887938Y-156439D01*
X887501Y-158189D01*
Y-159939D01*
X887938Y-161689D01*
X889030Y-163439D01*
X890340Y-164605D01*
X891868Y-164897D01*
X893396Y-164314D01*
X894925Y-162564D01*
G01X905656Y-164897D02*
Y-153231D01*
G01Y-155564D02*
X906748Y-154397D01*
X907840Y-153522D01*
X909368Y-153231D01*
X910459Y-153522D01*
X911770Y-154397D01*
G01X952413Y-192397D02*
X950666Y-192980D01*
X949356Y-194439D01*
X948483Y-196188D01*
X947828Y-198522D01*
X947610Y-201147D01*
X947828Y-203772D01*
X948483Y-206106D01*
X949356Y-207856D01*
X950666Y-209314D01*
X952413Y-209897D01*
X954159Y-209314D01*
X955470Y-207856D01*
X956343Y-206106D01*
X956998Y-203772D01*
X957216Y-201147D01*
X956998Y-198522D01*
X956343Y-196188D01*
X955470Y-194439D01*
X954159Y-192980D01*
X952413Y-192397D01*
G01X969913Y-209897D02*
X971441Y-209605D01*
X973188Y-208731D01*
X974280Y-207273D01*
X974716Y-205230D01*
X974280Y-203189D01*
X972970Y-201439D01*
X971005Y-200564D01*
X968821D01*
X967511Y-199980D01*
X966419Y-198522D01*
X965983Y-196481D01*
X966638Y-194439D01*
X968166Y-192980D01*
X969913Y-192397D01*
X971659Y-192980D01*
X973188Y-194439D01*
X973843Y-196481D01*
X973406Y-198522D01*
X972315Y-199980D01*
X971005Y-200564D01*
X968821D01*
X966856Y-201439D01*
X965546Y-203189D01*
X965110Y-205230D01*
X965546Y-207273D01*
X966638Y-208731D01*
X968385Y-209605D01*
X969913Y-209897D01*
G01X983483Y-210480D02*
X991343Y-192397D01*
G01X1004913D02*
X1003166Y-192980D01*
X1001856Y-194439D01*
X1000983Y-196188D01*
X1000328Y-198522D01*
X1000110Y-201147D01*
X1000328Y-203772D01*
X1000983Y-206106D01*
X1001856Y-207856D01*
X1003166Y-209314D01*
X1004913Y-209897D01*
X1006659Y-209314D01*
X1007970Y-207856D01*
X1008843Y-206106D01*
X1009498Y-203772D01*
X1009716Y-201147D01*
X1009498Y-198522D01*
X1008843Y-196188D01*
X1007970Y-194439D01*
X1006659Y-192980D01*
X1004913Y-192397D01*
G01X1022413Y-209897D02*
Y-192397D01*
X1019793Y-195897D01*
G01Y-209897D02*
X1025033D01*
G01X1035983Y-210480D02*
X1043843Y-192397D01*
G01X1053265Y-195314D02*
X1054575Y-193564D01*
X1056103Y-192689D01*
X1057850Y-192397D01*
X1060033Y-192980D01*
X1061561Y-194439D01*
X1061998Y-196188D01*
X1061780Y-197939D01*
X1060906Y-199397D01*
X1056540Y-202314D01*
X1054575Y-204355D01*
X1053265Y-207273D01*
X1052828Y-209897D01*
X1061998D01*
G01X1074913Y-192397D02*
X1073166Y-192980D01*
X1071856Y-194439D01*
X1070983Y-196188D01*
X1070328Y-198522D01*
X1070110Y-201147D01*
X1070328Y-203772D01*
X1070983Y-206106D01*
X1071856Y-207856D01*
X1073166Y-209314D01*
X1074913Y-209897D01*
X1076659Y-209314D01*
X1077970Y-207856D01*
X1078843Y-206106D01*
X1079498Y-203772D01*
X1079716Y-201147D01*
X1079498Y-198522D01*
X1078843Y-196188D01*
X1077970Y-194439D01*
X1076659Y-192980D01*
X1074913Y-192397D01*
G01X1092413Y-209897D02*
Y-192397D01*
X1089793Y-195897D01*
G01Y-209897D02*
X1095033D01*
G01X1112533D02*
Y-192397D01*
X1104454Y-204939D01*
X1115372D01*
G01X1000110Y-164897D02*
Y-147397D01*
X1004476D01*
X1006223Y-148272D01*
X1007533Y-149439D01*
X1008625Y-151188D01*
X1009498Y-153231D01*
X1009716Y-156147D01*
X1009498Y-159064D01*
X1008625Y-161106D01*
X1007533Y-162856D01*
X1006223Y-164022D01*
X1004476Y-164897D01*
X1000110D01*
G01X1026343D02*
Y-153231D01*
G01Y-155272D02*
X1025470Y-154106D01*
X1024159Y-153522D01*
X1022631Y-153231D01*
X1021103Y-153814D01*
X1019793Y-154980D01*
X1018919Y-156730D01*
X1018483Y-159064D01*
X1018919Y-161397D01*
X1019793Y-163147D01*
X1021103Y-164314D01*
X1022631Y-164897D01*
X1024159Y-164605D01*
X1025470Y-163731D01*
X1026343Y-162564D01*
G01X1039913Y-147397D02*
Y-164897D01*
G01X1036856Y-153231D02*
X1042970D01*
G01X1054138Y-157022D02*
X1061125D01*
X1060470Y-154980D01*
X1059378Y-153814D01*
X1057850Y-153231D01*
X1056321Y-153522D01*
X1055011Y-154397D01*
X1054138Y-156439D01*
X1053701Y-158189D01*
Y-159939D01*
X1054138Y-161689D01*
X1055230Y-163439D01*
X1056540Y-164605D01*
X1058068Y-164897D01*
X1059596Y-164314D01*
X1061125Y-162564D01*
G54D19*
G01X64403Y471046D02*
G02X66361Y471857I1958J-1958D01*
G01X69345D01*
G03X72348Y473101I0J4247D01*
G01X130673Y531427D01*
X132585Y533339D01*
G03X135799Y541100I-7761J7760D01*
G01Y582395D01*
G03X135300Y583600I-1704J0D01*
G03X130592Y585550I-4708J-4708D01*
G01X123099D01*
G02X120499Y588150I0J2600D01*
G01Y611206D01*
G02X120869Y611946I940J-7D01*
G03X121239Y612686I-570J747D01*
G01Y614036D01*
G03X120869Y614776I-940J-7D01*
G02X120499Y615516I570J747D01*
G01Y616866D01*
G02X120869Y617606I940J-8D01*
G03X121239Y618346I-570J747D01*
G01Y619696D01*
G03X120869Y620436I-940J-8D01*
G02X120499Y621176I570J747D01*
G01Y623229D01*
G02X121999Y626850I5121J0D01*
G02X123448Y627450I1449J-1449D01*
G01X130668D01*
G03X132599Y628250I0J2731D01*
G03X133599Y630664I-2414J2414D01*
G01Y639534D01*
G02X134248Y641101I2216J0D01*
G01X138848Y645701D01*
G02X140415Y646350I1567J-1567D01*
G01X143244D01*
G02X144238Y645356I0J-994D01*
G01Y649131D02*
G02X142657Y647550I-1581J0D01*
G01X140415D01*
G03X137999Y646550I-1J-3416D01*
G01X133399Y641950D01*
G03X132399Y639534I2416J-2415D01*
G01Y630665D01*
G02X131750Y629099I-2214J0D01*
G02X130667Y628650I-1083J1082D01*
G01X123449D01*
G03X121150Y627699I-2J-3249D01*
G03X119299Y623230I4470J-4469D01*
G01Y588150D01*
G03X123099Y584350I3800J0D01*
G01X130593D01*
G02X134451Y582751I-2J-5458D01*
G02X134598Y582395I-356J-356D01*
G01X134599Y582396D01*
Y541100D01*
G02X131736Y534188I-9775J0D01*
G01X129824Y532276D01*
X71499Y473950D01*
G02X69344Y473057I-2155J2154D01*
G01X66514D01*
G02X65271Y473572I1J1759D01*
G01X64397Y474446D01*
G01X64600Y486300D02*
G02X67509Y487505I2909J-2909D01*
G01X78819D01*
G03X82372Y488976I1J5024D01*
G01X111622Y518226D01*
G03X112823Y521126I-2901J2900D01*
G01Y625569D01*
G02X114099Y628650I4357J0D01*
G01X120949Y635500D01*
X121162Y635714D01*
G02X122699Y636350I1536J-1537D01*
G01X123799D01*
G02X125336Y635714I1J-2173D01*
G01X125499Y635550D01*
G01X64700Y489700D02*
G03X67102Y488705I2402J2402D01*
G01X78819D01*
G03X81523Y489825I0J3824D01*
G01X110773Y519075D01*
G03X111623Y521127I-2052J2052D01*
G01Y625569D01*
G02X113250Y629499I5557J1D01*
G01X120098Y636347D01*
X120312Y636562D01*
G02X122699Y637549I2384J-2386D01*
G01Y637550D01*
X123799D01*
G03X124311Y637762I0J724D01*
G01X125499Y638950D01*
G01X60003Y534150D02*
X60074Y534221D01*
G02X62399Y535184I2325J-2325D01*
G01X70044D01*
G02X72299Y534250I0J-3189D01*
G01X80457Y526092D01*
G03X83455Y524850I2998J2997D01*
G01X87099D01*
Y524851D01*
G03X89148Y525697I4J2896D01*
G01X89650Y526201D01*
X90749Y527300D01*
G03X91499Y529111I-1812J1811D01*
G01Y532943D01*
G03X91003Y534145I-1700J2D01*
G01X90694Y534454D01*
G03X89492Y534950I-1200J-1204D01*
G01X87594D01*
G02X87047Y535176I-1J773D01*
G01X86199Y536025D01*
G01X59999Y537550D02*
X60504Y537044D01*
G03X62099Y536384I1594J1595D01*
G01X69999D01*
G02X73181Y535066I0J-4500D01*
G01X81307Y526940D01*
G03X83456Y526050I2149J2149D01*
G01X87099D01*
G03X88298Y526546I1J1695D01*
G01X88800Y527049D01*
X89900Y528149D01*
G03X90299Y529112I-963J963D01*
G01Y532943D01*
G03X90153Y533296I-500J0D01*
G01X89845Y533604D01*
G03X89492Y533750I-353J-354D01*
G01X87023D01*
G03X86299Y533450I0J-1024D01*
G01X86199Y533350D01*
G03Y532250I550J-550D01*
G01X50410Y695801D02*
G02X53066Y696901I2656J-2656D01*
G01X64428D01*
G03X69852Y699148I0J7670D01*
G01X69853Y699147D01*
X83257Y712551D01*
G03X85099Y716999I-4450J4448D01*
G01Y924180D01*
G03X83248Y928648I-6318J0D01*
G01X83249Y928649D01*
X81749Y930149D01*
G02X80600Y932923I2774J2774D01*
G01Y939900D01*
G02X81591Y942293I3385J0D01*
G01X83799Y944501D01*
X83798Y944502D01*
G03X84900Y947162I-2659J2660D01*
G01Y971500D01*
G02X86537Y975452I5589J0D01*
G01X96592Y985507D01*
X96591Y985508D01*
G03X98450Y989993I-4486J4487D01*
G01Y1054127D01*
G02X99599Y1056901I3923J0D01*
G01X120860Y1078162D01*
G02X122400Y1078800I1540J-1540D01*
G02X123673Y1078272I-1J-1801D01*
G01X124423Y1077523D01*
G01X50300Y699200D02*
G03X52953Y698101I2653J2653D01*
G01X64429D01*
G03X69004Y699996I0J6470D01*
G01X82408Y713400D01*
G03X83899Y717000I-3601J3600D01*
G01Y924181D01*
G03X82400Y927800I-5118J0D01*
G01X80900Y929300D01*
X80901Y929301D01*
G02X79400Y932924I3622J3623D01*
G01Y939901D01*
G02X80742Y943142I4585J0D01*
G01X82950Y945350D01*
G03X83700Y947161I-1811J1811D01*
G01Y971501D01*
G02X85688Y976301I6789J0D01*
G01X95743Y986356D01*
G03X97250Y989994I-3638J3638D01*
G01Y1054126D01*
G02X98751Y1057749I5123J0D01*
G01X98750Y1057750D01*
X120011Y1079011D01*
G02X122399Y1080000I2388J-2389D01*
G01X122400D01*
G03X123844Y1080598I0J2042D01*
G01X124423Y1081177D01*
G01X47000Y1737100D02*
X46278Y1736378D01*
G03X45500Y1734500I1878J-1878D01*
G01Y1733477D01*
G02X45023Y1732325I-1629J0D01*
G01X44099Y1731401D01*
G03X42700Y1728024I3377J-3377D01*
G01Y1724000D01*
G03X43762Y1721436I3626J0D01*
G01X45099Y1720099D01*
G03X47752Y1719000I2653J2653D01*
G01X67041D01*
G03X70901Y1720599I0J5459D01*
G01X75201Y1724899D01*
G02X81001Y1727300I5798J-5800D01*
G01X121078D01*
G02X127598Y1724598I-2J-9223D01*
G01X127599Y1724599D01*
X144515Y1707683D01*
G02X147200Y1701198I-6484J-6483D01*
G01Y1678184D01*
G03X149099Y1673599I6484J0D01*
G01X165849Y1656849D01*
X165848Y1656848D01*
G02X168200Y1651173I-5676J-5677D01*
G01Y1597499D01*
G02X165021Y1589823I-10857J0D01*
G01X138284Y1563086D01*
G03X135349Y1556000I7086J-7086D01*
G01Y1352499D01*
G02X133336Y1347638I-6876J0D01*
G01X132849Y1347151D01*
G02X129411Y1345727I-3438J3439D01*
G01X116462D01*
G03X113500Y1344500I0J-4189D01*
G01X43600Y1737100D02*
X43628Y1737072D01*
G02X44300Y1735450I-1622J-1622D01*
G01Y1733476D01*
X44299Y1733477D01*
G02X44174Y1733174I-428J-1D01*
G01X43250Y1732250D01*
X43251Y1732249D01*
G03X41500Y1728025I4225J-4226D01*
G01Y1724001D01*
G03X42913Y1720587I4826J-2D01*
G01X44250Y1719250D01*
X44251Y1719251D01*
G03X47751Y1717800I3502J3501D01*
G01X67042D01*
G03X71749Y1719751I-2J6659D01*
G01X71750Y1719750D01*
X76050Y1724050D01*
G02X81000Y1726100I4950J-4951D01*
G01X121077D01*
G02X126750Y1723750I0J-8023D01*
G01X143666Y1706834D01*
G02X146000Y1701199I-5635J-5635D01*
G01Y1678185D01*
G03X148251Y1672751I7684J0D01*
G01X148250Y1672750D01*
X165000Y1656000D01*
G02X167000Y1651172I-4828J-4828D01*
G01Y1597500D01*
G02X164172Y1590672I-9657J0D01*
G01X137435Y1563935D01*
G03X134149Y1555999I7935J-7934D01*
G01Y1538840D01*
G02X133779Y1538100I-940J7D01*
G03X133409Y1537360I570J-747D01*
G01Y1536010D01*
G03X133779Y1535270I940J7D01*
G02X134149Y1534530I-570J-747D01*
G01Y1533180D01*
G02X133779Y1532440I-940J7D01*
G03X133409Y1531700I570J-747D01*
G01Y1530350D01*
G03X133779Y1529610I940J7D01*
G02X134149Y1528870I-570J-747D01*
G01Y1527520D01*
G02X133779Y1526780I-940J7D01*
G03X133409Y1526040I570J-747D01*
G01Y1524690D01*
G03X133779Y1523950I940J7D01*
G02X134149Y1523210I-570J-747D01*
G01Y1521860D01*
G02X133779Y1521120I-940J7D01*
G03X133409Y1520380I570J-747D01*
G01Y1519030D01*
G03X133779Y1518290I940J7D01*
G02X134149Y1517550I-570J-747D01*
G01Y1516200D01*
G02X133779Y1515460I-940J7D01*
G03X133409Y1514720I570J-747D01*
G01Y1513370D01*
G03X133779Y1512630I940J7D01*
G02X134149Y1511890I-570J-747D01*
G01Y1439883D01*
G02X133779Y1439143I-940J7D01*
G03X133409Y1438403I570J-748D01*
G01Y1437053D01*
G03X133779Y1436313I940J7D01*
G02X134149Y1435573I-570J-748D01*
G01Y1434223D01*
G02X133779Y1433483I-940J7D01*
G03X133409Y1432743I570J-748D01*
G01Y1431393D01*
G03X133779Y1430653I940J7D01*
G02X134149Y1429913I-570J-748D01*
G01Y1428563D01*
G02X133779Y1427823I-940J7D01*
G03X133409Y1427083I570J-748D01*
G01Y1425733D01*
G03X133779Y1424993I940J7D01*
G02X134149Y1424253I-570J-748D01*
G01Y1422903D01*
G02X133779Y1422163I-940J7D01*
G03X133409Y1421423I570J-748D01*
G01Y1420073D01*
G03X133779Y1419333I940J7D01*
G02X134149Y1418593I-570J-748D01*
G01Y1417243D01*
G02X133779Y1416503I-940J7D01*
G03X133409Y1415763I570J-748D01*
G01Y1414413D01*
G03X133779Y1413673I940J7D01*
G02X134149Y1412933I-570J-748D01*
G01Y1352500D01*
G02X132487Y1348487I-5676J0D01*
G01X132000Y1348000D01*
G02X129410Y1346927I-2590J2590D01*
G01X116462D01*
G02X113500Y1348154I0J4189D01*
G01X45877Y1728477D02*
G03X48839Y1727250I2962J2962D01*
G01X66293D01*
G03X70152Y1728848I0J5458D01*
G01X70151Y1728849D01*
X71701Y1730399D01*
G02X77501Y1732800I5798J-5800D01*
G01X110085D01*
G03X112004Y1733595I0J2714D01*
G01X118554Y1740145D01*
X118555Y1740144D01*
G02X122306Y1741699I3753J-3752D01*
G01X183443D01*
G02X186593Y1740393I-2J-4457D01*
G01X186594Y1740394D01*
X188994Y1737994D01*
G02X190274Y1734902I-3092J-3091D01*
G01Y1123372D01*
G02X188298Y1118602I-6745J0D01*
G01X188299Y1118601D01*
X150210Y1080512D01*
G02X146001Y1078769I-4209J4211D01*
G01X140407D01*
G03X137481Y1077557I0J-4138D01*
G01X137477Y1081177D02*
G03X140393Y1079969I2916J2916D01*
G01X146000D01*
G03X149361Y1081361I0J4754D01*
G01X187450Y1119450D01*
G03X189074Y1123371I-3921J3921D01*
G01Y1561401D01*
G03X188704Y1562141I-940J-8D01*
G02X188334Y1562881I570J747D01*
G01Y1564231D01*
G02X188704Y1564971I940J-8D01*
G03X189074Y1565711I-570J747D01*
G01Y1581048D01*
G03X188704Y1581788I-940J-8D01*
G02X188334Y1582528I570J747D01*
G01Y1583878D01*
G02X188704Y1584618I940J-8D01*
G03X189074Y1585358I-570J747D01*
G01Y1586708D01*
G03X188704Y1587448I-940J-8D01*
G02X188334Y1588188I570J747D01*
G01Y1589538D01*
G02X188704Y1590278I940J-8D01*
G03X189074Y1591018I-570J747D01*
G01Y1592368D01*
G03X188704Y1593108I-940J-8D01*
G02X188334Y1593848I570J747D01*
G01Y1595198D01*
G02X188704Y1595938I940J-8D01*
G03X189074Y1596678I-570J747D01*
G01Y1598028D01*
G03X188704Y1598768I-940J-8D01*
G02X188334Y1599508I570J747D01*
G01Y1600858D01*
G02X188704Y1601598I940J-8D01*
G03X189074Y1602338I-570J747D01*
G01Y1734902D01*
G03X188145Y1737145I-3172J0D01*
G01X185745Y1739545D01*
G03X183442Y1740499I-2303J-2303D01*
G01X122307D01*
G03X119403Y1739296I0J-4107D01*
G01X112853Y1732746D01*
X112852Y1732747D01*
G02X110086Y1731600I-2768J2767D01*
G01X101002D01*
G03X100262Y1731230I8J-940D01*
G02X99522Y1730860I-747J570D01*
G01X98172D01*
G02X97432Y1731230I8J940D01*
G03X96692Y1731600I-747J-570D01*
G01X95342D01*
G03X94602Y1731230I8J-940D01*
G02X93862Y1730860I-747J570D01*
G01X92512D01*
G02X91772Y1731230I8J940D01*
G03X91032Y1731600I-747J-570D01*
G01X89682D01*
G03X88942Y1731230I8J-940D01*
G02X88202Y1730860I-747J570D01*
G01X86852D01*
G02X86112Y1731230I8J940D01*
G03X85372Y1731600I-747J-570D01*
G01X84022D01*
G03X83282Y1731230I8J-940D01*
G02X82542Y1730860I-747J570D01*
G01X81192D01*
G02X80452Y1731230I8J940D01*
G03X79712Y1731600I-747J-570D01*
G01X77500D01*
G03X72550Y1729550I0J-7001D01*
G01X71000Y1728000D01*
G02X66292Y1726050I-4708J4708D01*
G01X48839D01*
G03X45877Y1724823I0J-4189D01*
M02*
